FILE_TYPE = MACRO_DRAWING;
SET COLOR_WIRE YELLOW;
SET COLOR_PROP ORANGE;
SET COLOR_DOT WHITE;
SET COLOR_ARC YELLOW;
SET COLOR_BODY GREEN;
SET COLOR_NOTE PURPLE;
SET PROP_DISPLAY VALUE;
SET PAGE_NUMBER P3;
FORCEADD GND_SG..1
(-750 5250);
FORCEPROP 3 LASTPIN (-700 5300) SIG_NAME SG\g
J 0
(-690 5310);
DISPLAY 0.659574 (-690 5310);
PAINT MONO (-690 5310);
DISPLAY INVISIBLE (-690 5310);
FORCEPROP 1 LAST HDL_POWER SG
J 1
(-695 5155);
DISPLAY 0.808511 (-695 5155);
PAINT GREEN (-695 5155);
FORCEPROP 1 LAST CDS_LMAN_SYM_OUTLINE 0,0,100,-50
J 0
(-750 5250);
DISPLAY 0.468085 (-750 5250);
PAINT GREEN (-750 5250);
DISPLAY INVISIBLE (-750 5250);
FORCEPROP 2 LAST CDS_LIB cls
J 0
(-750 5250);
DISPLAY INVISIBLE (-750 5250);
FORCEPROP 1 LAST BODY_TYPE PLUMBING
J 0
(-735 5235);
DISPLAY 0.808511 (-735 5235);
PAINT GREEN (-735 5235);
DISPLAY INVISIBLE (-735 5235);
FORCEPROP 1 LAST PATH I1
J 0
(-715 5250);
DISPLAY 0.808511 (-715 5250);
PAINT GREEN (-715 5250);
DISPLAY INVISIBLE (-715 5250);
FORCEADD OFFPAGE_OUT..1
R 2
(-9650 6250);
FORCEPROP 2 LAST $XR0 10C5< 
J 0
(-9833 6250);
DISPLAY 0.638298 (-9833 6250);
PAINT MONO (-9833 6250);
FORCEPROP 1 LAST BODY_TYPE COMMENT
J 2
(-9660 6385);
DISPLAY 0.808511 (-9660 6385);
PAINT GREEN (-9660 6385);
DISPLAY INVISIBLE (-9660 6385);
FORCEPROP 1 LAST CDS_LMAN_SYM_OUTLINE -50,50,50,-50
J 2
(-9650 6250);
DISPLAY 0.468085 (-9650 6250);
PAINT GREEN (-9650 6250);
DISPLAY INVISIBLE (-9650 6250);
FORCEPROP 2 LAST CDS_LIB cls
J 0
(-9650 6250);
DISPLAY INVISIBLE (-9650 6250);
FORCEPROP 1 LAST OFFPAGE TRUE
J 2
(-9660 6305);
DISPLAY 0.808511 (-9660 6305);
PAINT GREEN (-9660 6305);
DISPLAY INVISIBLE (-9660 6305);
FORCEPROP 2 LAST PATH I10
J 0
(-9800 6300);
DISPLAY 1.021277 (-9800 6300);
DISPLAY INVISIBLE (-9800 6300);
FORCEADD G220_10198_01..1
(-6700 2400);
FORCEPROP 1 LAST $LOCATION U2
J 0
(-6650 2500);
DISPLAY 1.212766 (-6650 2500);
PAINT GREEN (-6650 2500);
FORCEPROP 0 LAST CDS_LOCATION U2
J 0
(-6650 2750);
DISPLAY 1.021277 (-6650 2750);
DISPLAY INVISIBLE (-6650 2750);
FORCEPROP 0 LAST $SEC 1
J 0
(-6650 2750);
DISPLAY 0.680851 (-6650 2750);
PAINT MONO (-6650 2750);
DISPLAY INVISIBLE (-6650 2750);
FORCEPROP 0 LAST CDS_SEC 1
J 0
(-6650 2750);
DISPLAY 1.021277 (-6650 2750);
DISPLAY INVISIBLE (-6650 2750);
FORCEPROP 0 LASTPIN (-6800 2100) $PN 1
J 2
(-6810 2110);
DISPLAY 0.680851 (-6810 2110);
PAINT MONO (-6810 2110);
FORCEPROP 0 LASTPIN (-5900 1800) $PN 4
J 0
(-5890 1810);
DISPLAY 0.680851 (-5890 1810);
PAINT MONO (-5890 1810);
FORCEPROP 0 LASTPIN (-5900 2000) $PN 5
J 0
(-5890 2010);
DISPLAY 0.680851 (-5890 2010);
PAINT MONO (-5890 2010);
FORCEPROP 0 LASTPIN (-6800 1800) $PN 3
J 2
(-6810 1810);
DISPLAY 0.680851 (-6810 1810);
PAINT MONO (-6810 1810);
FORCEPROP 0 LASTPIN (-5900 2200) $PN 2
J 0
(-5890 2210);
DISPLAY 0.680851 (-5890 2210);
PAINT MONO (-5890 2210);
FORCEPROP 0 LASTPIN (-6800 1900) $PN 6
J 2
(-6810 1910);
DISPLAY 0.680851 (-6810 1910);
PAINT MONO (-6810 1910);
FORCEPROP 0 LASTPIN (-5900 2300) $PN 7
J 0
(-5890 2310);
DISPLAY 0.680851 (-5890 2310);
PAINT MONO (-5890 2310);
FORCEPROP 0 LASTPIN (-6800 2300) $PN 8
J 2
(-6810 2310);
DISPLAY 0.680851 (-6810 2310);
PAINT MONO (-6810 2310);
FORCEPROP 0 LAST NO_ASSY TRUE
J 0
(-6700 1600);
DISPLAY 1.021277 (-6700 1600);
DISPLAY BOTH (-6700 1600);
FORCEPROP 1 LAST CLS_PN G223-10197-01
J 0
(-6650 2600);
DISPLAY 1.212766 (-6650 2600);
PAINT GREEN (-6650 2600);
FORCEPROP 0 LAST PART_NUMBER PCA9510AD,118
J 0
(-6650 2700);
DISPLAY 1.021277 (-6650 2700);
FORCEPROP 1 LAST PATH I100
J 0
(-6650 2450);
DISPLAY 1.212766 (-6650 2450);
PAINT GREEN (-6650 2450);
DISPLAY INVISIBLE (-6650 2450);
FORCEPROP 1 LAST CDS_LMAN_SYM_OUTLINE 0,0,700,-700
J 0
(-6700 2400);
DISPLAY 0.468085 (-6700 2400);
PAINT GREEN (-6700 2400);
DISPLAY INVISIBLE (-6700 2400);
FORCEPROP 2 LAST CDS_LIB stdlogic
J 0
(-6700 2400);
DISPLAY INVISIBLE (-6700 2400);
FORCEPROP 2 LASTPIN (-6800 2100) SIG_NAME UN$3$G2201019801$I100$EN
J 0
(-6790 2110);
DISPLAY 0.659574 (-6790 2110);
PAINT MONO (-6790 2110);
DISPLAY INVISIBLE (-6790 2110);
FORCEADD RESISTOR..2
(-7350 2600);
FORCEPROP 1 LAST $LOCATION R25
J 0
(-7300 2450);
DISPLAY 1.212766 (-7300 2450);
PAINT GREEN (-7300 2450);
FORCEPROP 0 LAST CDS_LOCATION R25
J 0
(-7300 2700);
DISPLAY 1.021277 (-7300 2700);
DISPLAY INVISIBLE (-7300 2700);
FORCEPROP 0 LAST $SEC 1
J 0
(-7300 2700);
DISPLAY 0.680851 (-7300 2700);
PAINT MONO (-7300 2700);
DISPLAY INVISIBLE (-7300 2700);
FORCEPROP 0 LAST CDS_SEC 1
J 0
(-7300 2700);
DISPLAY 1.021277 (-7300 2700);
DISPLAY INVISIBLE (-7300 2700);
FORCEPROP 0 LASTPIN (-7350 2700) $PN 1
R 1
J 0
(-7360 2710);
DISPLAY 0.680851 (-7360 2710);
PAINT MONO (-7360 2710);
FORCEPROP 0 LASTPIN (-7350 2450) $PN 2
R 1
J 2
(-7360 2440);
DISPLAY 0.680851 (-7360 2440);
PAINT MONO (-7360 2440);
FORCEPROP 0 LAST PACKAGE 0402
J 0
(-7300 2750);
DISPLAY 0.808511 (-7300 2750);
FORCEPROP 1 LAST VALUE 4.7KOHM
J 0
(-7300 2650);
DISPLAY 0.978723 (-7300 2650);
PAINT GREEN (-7300 2650);
FORCEPROP 0 LAST NO_ASSY TRUE
J 0
(-7300 2550);
DISPLAY 0.638298 (-7300 2550);
DISPLAY BOTH (-7300 2550);
FORCEPROP 1 LAST PATH I103
J 0
(-7547 2705);
DISPLAY 1.212766 (-7547 2705);
PAINT GREEN (-7547 2705);
DISPLAY INVISIBLE (-7547 2705);
FORCEPROP 1 LAST TOLERANCE 1%
J 0
(-7547 2855);
DISPLAY 1.212766 (-7547 2855);
PAINT GREEN (-7547 2855);
DISPLAY INVISIBLE (-7547 2855);
FORCEPROP 1 LAST CLS_PN G155-14701-01
J 0
(-7486 2800);
DISPLAY 1.212766 (-7486 2800);
PAINT GREEN (-7486 2800);
DISPLAY INVISIBLE (-7486 2800);
FORCEPROP 1 LAST CDS_LMAN_SYM_OUTLINE -50,50,50,-100
J 0
(-7350 2600);
DISPLAY 0.468085 (-7350 2600);
PAINT GREEN (-7350 2600);
DISPLAY INVISIBLE (-7350 2600);
FORCEPROP 2 LAST CDS_LIB passive
J 0
(-7350 2600);
DISPLAY INVISIBLE (-7350 2600);
FORCEADD OFFPAGE_BI..2
R 2
(-3800 2300);
FORCEPROP 2 LAST $XR0 16D4<> 
J 0
(-3740 2300);
DISPLAY 0.638298 (-3740 2300);
PAINT MONO (-3740 2300);
FORCEPROP 2 LAST $XR1 16H3<> 
J 0
(-3530 2300);
DISPLAY 0.638298 (-3530 2300);
PAINT MONO (-3530 2300);
FORCEPROP 1 LAST BODY_TYPE COMMENT
J 2
(-3810 2435);
DISPLAY 0.808511 (-3810 2435);
PAINT GREEN (-3810 2435);
DISPLAY INVISIBLE (-3810 2435);
FORCEPROP 1 LAST CDS_LMAN_SYM_OUTLINE -50,50,50,-50
J 2
(-3800 2300);
DISPLAY 0.468085 (-3800 2300);
PAINT GREEN (-3800 2300);
DISPLAY INVISIBLE (-3800 2300);
FORCEPROP 2 LAST CDS_LIB cls
J 2
(-3800 2300);
DISPLAY INVISIBLE (-3800 2300);
FORCEPROP 1 LAST OFFPAGE TRUE
J 2
(-3810 2355);
DISPLAY 0.808511 (-3810 2355);
PAINT GREEN (-3810 2355);
DISPLAY INVISIBLE (-3810 2355);
FORCEPROP 2 LAST PATH I109
J 2
(-3850 2400);
DISPLAY 1.021277 (-3850 2400);
DISPLAY INVISIBLE (-3850 2400);
FORCEADD OFFPAGE_OUT..1
R 2
(-9650 6150);
FORCEPROP 2 LAST $XR0 10C5< 
J 0
(-9833 6150);
DISPLAY 0.638298 (-9833 6150);
PAINT MONO (-9833 6150);
FORCEPROP 2 LAST CDS_LIB cls
J 0
(-9650 6150);
DISPLAY INVISIBLE (-9650 6150);
FORCEPROP 1 LAST CDS_LMAN_SYM_OUTLINE -50,50,50,-50
J 2
(-9650 6150);
DISPLAY 0.468085 (-9650 6150);
PAINT GREEN (-9650 6150);
DISPLAY INVISIBLE (-9650 6150);
FORCEPROP 1 LAST BODY_TYPE COMMENT
J 2
(-9660 6285);
DISPLAY 0.808511 (-9660 6285);
PAINT GREEN (-9660 6285);
DISPLAY INVISIBLE (-9660 6285);
FORCEPROP 1 LAST OFFPAGE TRUE
J 2
(-9660 6205);
DISPLAY 0.808511 (-9660 6205);
PAINT GREEN (-9660 6205);
DISPLAY INVISIBLE (-9660 6205);
FORCEPROP 2 LAST PATH I11
J 0
(-9800 6200);
DISPLAY 1.021277 (-9800 6200);
DISPLAY INVISIBLE (-9800 6200);
FORCEADD OFFPAGE_OUT..1
(-3800 2200);
FORCEPROP 2 LAST $XR0 16D4< 
J 0
(-3745 2200);
DISPLAY 0.638298 (-3745 2200);
PAINT MONO (-3745 2200);
FORCEPROP 2 LAST $XR1 16H3< 
J 0
(-3565 2200);
DISPLAY 0.638298 (-3565 2200);
PAINT MONO (-3565 2200);
FORCEPROP 1 LAST BODY_TYPE COMMENT
J 0
(-3790 2335);
DISPLAY 0.808511 (-3790 2335);
PAINT GREEN (-3790 2335);
DISPLAY INVISIBLE (-3790 2335);
FORCEPROP 1 LAST CDS_LMAN_SYM_OUTLINE -50,50,50,-50
J 0
(-3800 2200);
DISPLAY 0.468085 (-3800 2200);
PAINT GREEN (-3800 2200);
DISPLAY INVISIBLE (-3800 2200);
FORCEPROP 2 LAST CDS_LIB cls
J 0
(-3800 2200);
DISPLAY INVISIBLE (-3800 2200);
FORCEPROP 1 LAST OFFPAGE TRUE
J 0
(-3790 2255);
DISPLAY 0.808511 (-3790 2255);
PAINT GREEN (-3790 2255);
DISPLAY INVISIBLE (-3790 2255);
FORCEPROP 2 LAST PATH I110
J 0
(-3750 2300);
DISPLAY 1.021277 (-3750 2300);
DISPLAY INVISIBLE (-3750 2300);
FORCEADD VCC..1
(-750 6250);
FORCEPROP 3 LASTPIN (-700 6200) SIG_NAME XP3R3V_FPGA\g
J 0
(-690 6210);
DISPLAY 0.659574 (-690 6210);
PAINT MONO (-690 6210);
DISPLAY INVISIBLE (-690 6210);
FORCEPROP 1 LAST HDL_POWER XP3R3V_FPGA
J 1
(-695 6305);
DISPLAY 1.021277 (-695 6305);
PAINT GREEN (-695 6305);
FORCEPROP 0 LAST VOLTAGE 3.3V
J 0
(-1000 6400);
DISPLAY 1.021277 (-1000 6400);
DISPLAY BOTH (-1000 6400);
FORCEPROP 1 LAST CDS_LMAN_SYM_OUTLINE -250,250,250,-250
J 0
(-750 6250);
DISPLAY 0.468085 (-750 6250);
PAINT GREEN (-750 6250);
DISPLAY INVISIBLE (-750 6250);
FORCEPROP 2 LAST CDS_LIB cls
J 0
(-750 6250);
DISPLAY INVISIBLE (-750 6250);
FORCEPROP 1 LAST PATH I111
J 0
(-715 6340);
DISPLAY 0.808511 (-715 6340);
PAINT GREEN (-715 6340);
DISPLAY INVISIBLE (-715 6340);
FORCEPROP 1 LAST BODY_TYPE PLUMBING
J 0
(-795 6207);
DISPLAY 0.340426 (-795 6207);
PAINT GREEN (-795 6207);
DISPLAY INVISIBLE (-795 6207);
FORCEADD VCC..1
(-7950 3000);
FORCEPROP 3 LASTPIN (-7900 2950) SIG_NAME XP3R3V_FPGA\g
J 0
(-7890 2960);
DISPLAY 0.659574 (-7890 2960);
PAINT MONO (-7890 2960);
DISPLAY INVISIBLE (-7890 2960);
FORCEPROP 1 LAST HDL_POWER XP3R3V_FPGA
J 1
(-7895 3055);
DISPLAY 1.021277 (-7895 3055);
PAINT GREEN (-7895 3055);
FORCEPROP 0 LAST VOLTAGE 3.3V
J 0
(-8200 3150);
DISPLAY 1.021277 (-8200 3150);
DISPLAY BOTH (-8200 3150);
FORCEPROP 1 LAST PATH I112
J 0
(-7915 3090);
DISPLAY 0.808511 (-7915 3090);
PAINT GREEN (-7915 3090);
DISPLAY INVISIBLE (-7915 3090);
FORCEPROP 1 LAST BODY_TYPE PLUMBING
J 0
(-7995 2957);
DISPLAY 0.340426 (-7995 2957);
PAINT GREEN (-7995 2957);
DISPLAY INVISIBLE (-7995 2957);
FORCEPROP 1 LAST CDS_LMAN_SYM_OUTLINE -250,250,250,-250
J 0
(-7950 3000);
DISPLAY 0.468085 (-7950 3000);
PAINT GREEN (-7950 3000);
DISPLAY INVISIBLE (-7950 3000);
FORCEPROP 2 LAST CDS_LIB cls
J 0
(-7950 3000);
DISPLAY INVISIBLE (-7950 3000);
FORCEADD OFFPAGE_IN..1
(-9550 2100);
FORCEPROP 2 LAST $XR0 12H5> 
J 0
(-9733 2100);
DISPLAY 0.638298 (-9733 2100);
PAINT MONO (-9733 2100);
FORCEPROP 2 LAST PATH I113
J 0
(-9500 2200);
DISPLAY 1.021277 (-9500 2200);
DISPLAY INVISIBLE (-9500 2200);
FORCEPROP 1 LAST OFFPAGE TRUE
J 0
(-9540 2155);
DISPLAY 0.808511 (-9540 2155);
PAINT GREEN (-9540 2155);
DISPLAY INVISIBLE (-9540 2155);
FORCEPROP 1 LAST BODY_TYPE COMMENT
J 0
(-9540 2235);
DISPLAY 0.808511 (-9540 2235);
PAINT GREEN (-9540 2235);
DISPLAY INVISIBLE (-9540 2235);
FORCEPROP 1 LAST CDS_LMAN_SYM_OUTLINE -50,50,50,-50
J 0
(-9550 2100);
DISPLAY 0.468085 (-9550 2100);
PAINT GREEN (-9550 2100);
DISPLAY INVISIBLE (-9550 2100);
FORCEPROP 2 LAST CDS_LIB cls
J 0
(-9550 2100);
DISPLAY INVISIBLE (-9550 2100);
FORCEADD RESISTOR..1
(-7900 2100);
FORCEPROP 1 LAST $LOCATION R354
J 2
(-8050 2100);
DISPLAY 1.212766 (-8050 2100);
PAINT GREEN (-8050 2100);
FORCEPROP 0 LAST CDS_LOCATION R354
J 0
(-7700 2200);
DISPLAY 1.021277 (-7700 2200);
DISPLAY INVISIBLE (-7700 2200);
FORCEPROP 0 LAST $SEC 1
J 0
(-7700 2200);
DISPLAY 0.680851 (-7700 2200);
PAINT MONO (-7700 2200);
DISPLAY INVISIBLE (-7700 2200);
FORCEPROP 0 LAST CDS_SEC 1
J 0
(-7700 2200);
DISPLAY 1.021277 (-7700 2200);
DISPLAY INVISIBLE (-7700 2200);
FORCEPROP 0 LASTPIN (-8000 2100) $PN 1
J 2
(-8010 2110);
DISPLAY 0.680851 (-8010 2110);
PAINT MONO (-8010 2110);
FORCEPROP 0 LASTPIN (-7750 2100) $PN 2
J 0
(-7740 2110);
DISPLAY 0.680851 (-7740 2110);
PAINT MONO (-7740 2110);
FORCEPROP 1 LAST VALUE 33OHM
J 0
(-7700 2100);
DISPLAY 1.234043 (-7700 2100);
PAINT GREEN (-7700 2100);
FORCEPROP 0 LAST PACKAGE 0402
J 0
(-7950 2150);
DISPLAY 0.808511 (-7950 2150);
FORCEPROP 0 LAST NO_ASSY TRUE
J 0
(-8050 2050);
DISPLAY 0.638298 (-8050 2050);
DISPLAY BOTH (-8050 2050);
FORCEPROP 1 LAST PATH I114
J 0
(-8097 2205);
DISPLAY 1.212766 (-8097 2205);
PAINT GREEN (-8097 2205);
DISPLAY INVISIBLE (-8097 2205);
FORCEPROP 1 LAST TOLERANCE 1%
J 0
(-8097 2355);
DISPLAY 1.212766 (-8097 2355);
PAINT GREEN (-8097 2355);
DISPLAY INVISIBLE (-8097 2355);
FORCEPROP 1 LAST CLS_PN G155-133R0-01
J 0
(-8036 2300);
DISPLAY 1.212766 (-8036 2300);
PAINT GREEN (-8036 2300);
DISPLAY INVISIBLE (-8036 2300);
FORCEPROP 2 LAST CDS_LIB passive
J 0
(-7900 2100);
DISPLAY INVISIBLE (-7900 2100);
FORCEPROP 1 LAST CDS_LMAN_SYM_OUTLINE -50,50,100,-50
J 0
(-7900 2100);
DISPLAY 0.468085 (-7900 2100);
PAINT GREEN (-7900 2100);
DISPLAY INVISIBLE (-7900 2100);
FORCEPROP 2 LAST SIGNAL_MODEL DEFAULT_RESISTOR_33OHM_2_1
J 0
(-8050 2300);
DISPLAY 1.021277 (-8050 2300);
DISPLAY INVISIBLE (-8050 2300);
FORCEADD CAPACITOR..1
(-4000 6450);
FORCEPROP 1 LAST LOCATION C25
J 2
(-4150 6450);
DISPLAY 1.212766 (-4150 6450);
PAINT GREEN (-4150 6450);
FORCEPROP 0 LAST $SEC 1
J 0
(-3750 6550);
DISPLAY 0.680851 (-3750 6550);
PAINT MONO (-3750 6550);
DISPLAY INVISIBLE (-3750 6550);
FORCEPROP 0 LAST CDS_SEC 1
J 0
(-3750 6550);
DISPLAY 1.021277 (-3750 6550);
DISPLAY INVISIBLE (-3750 6550);
FORCEPROP 0 LASTPIN (-4100 6450) $PN 1
J 2
(-4110 6460);
DISPLAY 0.680851 (-4110 6460);
PAINT MONO (-4110 6460);
FORCEPROP 0 LASTPIN (-3850 6450) $PN 2
J 0
(-3840 6460);
DISPLAY 0.680851 (-3840 6460);
PAINT MONO (-3840 6460);
FORCEPROP 1 LAST VALUE 0.1UF
J 0
(-3750 6450);
DISPLAY 1.212766 (-3750 6450);
PAINT GREEN (-3750 6450);
FORCEPROP 0 LAST PACKAGE 0402
J 0
(-3450 6450);
DISPLAY 1.021277 (-3450 6450);
FORCEPROP 1 LAST TOLERANCE 10%
J 2
(-4100 6550);
DISPLAY 1.212766 (-4100 6550);
PAINT GREEN (-4100 6550);
DISPLAY INVISIBLE (-4100 6550);
FORCEPROP 2 LAST SIGNAL_MODEL DEFAULT_CAPACITOR_100000pF_1_2
J 0
(-4050 6650);
DISPLAY 1.021277 (-4050 6650);
DISPLAY INVISIBLE (-4050 6650);
FORCEPROP 1 LAST CLS_PN G105-0B104-CK
J 2
(-4050 6550);
DISPLAY 1.212766 (-4050 6550);
PAINT GREEN (-4050 6550);
DISPLAY INVISIBLE (-4050 6550);
FORCEPROP 1 LAST CDS_LMAN_SYM_OUTLINE 0,50,50,-50
J 0
(-4000 6450);
DISPLAY 0.468085 (-4000 6450);
PAINT GREEN (-4000 6450);
DISPLAY INVISIBLE (-4000 6450);
FORCEPROP 2 LAST CDS_LIB passive
J 0
(-4000 6450);
DISPLAY INVISIBLE (-4000 6450);
FORCEPROP 1 LAST PATH I115
J 2
(-4050 6550);
DISPLAY 1.212766 (-4050 6550);
PAINT GREEN (-4050 6550);
DISPLAY INVISIBLE (-4050 6550);
FORCEADD CAPACITOR..1
(-4000 6050);
FORCEPROP 1 LAST LOCATION C26
J 2
(-4150 6050);
DISPLAY 1.212766 (-4150 6050);
PAINT GREEN (-4150 6050);
FORCEPROP 0 LAST $SEC 1
J 0
(-3750 6150);
DISPLAY 0.680851 (-3750 6150);
PAINT MONO (-3750 6150);
DISPLAY INVISIBLE (-3750 6150);
FORCEPROP 0 LAST CDS_SEC 1
J 0
(-3750 6150);
DISPLAY 1.021277 (-3750 6150);
DISPLAY INVISIBLE (-3750 6150);
FORCEPROP 0 LASTPIN (-4100 6050) $PN 1
J 2
(-4110 6060);
DISPLAY 0.680851 (-4110 6060);
PAINT MONO (-4110 6060);
FORCEPROP 0 LASTPIN (-3850 6050) $PN 2
J 0
(-3840 6060);
DISPLAY 0.680851 (-3840 6060);
PAINT MONO (-3840 6060);
FORCEPROP 0 LAST PACKAGE 0402
J 0
(-3450 6050);
DISPLAY 1.021277 (-3450 6050);
FORCEPROP 1 LAST VALUE 0.1UF
J 0
(-3750 6050);
DISPLAY 1.212766 (-3750 6050);
PAINT GREEN (-3750 6050);
FORCEPROP 1 LAST TOLERANCE 10%
J 2
(-4100 6150);
DISPLAY 1.212766 (-4100 6150);
PAINT GREEN (-4100 6150);
DISPLAY INVISIBLE (-4100 6150);
FORCEPROP 2 LAST SIGNAL_MODEL DEFAULT_CAPACITOR_100000pF_1_2
J 0
(-4050 6250);
DISPLAY 1.021277 (-4050 6250);
DISPLAY INVISIBLE (-4050 6250);
FORCEPROP 1 LAST CLS_PN G105-0B104-CK
J 2
(-4050 6150);
DISPLAY 1.212766 (-4050 6150);
PAINT GREEN (-4050 6150);
DISPLAY INVISIBLE (-4050 6150);
FORCEPROP 1 LAST CDS_LMAN_SYM_OUTLINE 0,50,50,-50
J 0
(-4000 6050);
DISPLAY 0.468085 (-4000 6050);
PAINT GREEN (-4000 6050);
DISPLAY INVISIBLE (-4000 6050);
FORCEPROP 2 LAST CDS_LIB passive
J 0
(-4000 6050);
DISPLAY INVISIBLE (-4000 6050);
FORCEPROP 1 LAST PATH I116
J 2
(-4050 6150);
DISPLAY 1.212766 (-4050 6150);
PAINT GREEN (-4050 6150);
DISPLAY INVISIBLE (-4050 6150);
FORCEADD CAPACITOR..1
(-4000 5950);
FORCEPROP 1 LAST LOCATION C27
J 2
(-4150 5950);
DISPLAY 1.212766 (-4150 5950);
PAINT GREEN (-4150 5950);
FORCEPROP 0 LAST $SEC 1
J 0
(-3750 6050);
DISPLAY 0.680851 (-3750 6050);
PAINT MONO (-3750 6050);
DISPLAY INVISIBLE (-3750 6050);
FORCEPROP 0 LAST CDS_SEC 1
J 0
(-3750 6050);
DISPLAY 1.021277 (-3750 6050);
DISPLAY INVISIBLE (-3750 6050);
FORCEPROP 0 LASTPIN (-4100 5950) $PN 1
J 2
(-4110 5960);
DISPLAY 0.680851 (-4110 5960);
PAINT MONO (-4110 5960);
FORCEPROP 0 LASTPIN (-3850 5950) $PN 2
J 0
(-3840 5960);
DISPLAY 0.680851 (-3840 5960);
PAINT MONO (-3840 5960);
FORCEPROP 1 LAST VALUE 0.1UF
J 0
(-3750 5950);
DISPLAY 1.212766 (-3750 5950);
PAINT GREEN (-3750 5950);
FORCEPROP 0 LAST PACKAGE 0402
J 0
(-3450 5950);
DISPLAY 1.021277 (-3450 5950);
FORCEPROP 1 LAST TOLERANCE 10%
J 2
(-4100 6050);
DISPLAY 1.212766 (-4100 6050);
PAINT GREEN (-4100 6050);
DISPLAY INVISIBLE (-4100 6050);
FORCEPROP 2 LAST SIGNAL_MODEL DEFAULT_CAPACITOR_100000pF_1_2
J 0
(-4050 6150);
DISPLAY 1.021277 (-4050 6150);
DISPLAY INVISIBLE (-4050 6150);
FORCEPROP 1 LAST CLS_PN G105-0B104-CK
J 2
(-4050 6050);
DISPLAY 1.212766 (-4050 6050);
PAINT GREEN (-4050 6050);
DISPLAY INVISIBLE (-4050 6050);
FORCEPROP 1 LAST CDS_LMAN_SYM_OUTLINE 0,50,50,-50
J 0
(-4000 5950);
DISPLAY 0.468085 (-4000 5950);
PAINT GREEN (-4000 5950);
DISPLAY INVISIBLE (-4000 5950);
FORCEPROP 2 LAST CDS_LIB passive
J 0
(-4000 5950);
DISPLAY INVISIBLE (-4000 5950);
FORCEPROP 1 LAST PATH I117
J 2
(-4050 6050);
DISPLAY 1.212766 (-4050 6050);
PAINT GREEN (-4050 6050);
DISPLAY INVISIBLE (-4050 6050);
FORCEADD CAPACITOR..1
(-4000 5650);
FORCEPROP 1 LAST LOCATION C28
J 2
(-4150 5650);
DISPLAY 1.212766 (-4150 5650);
PAINT GREEN (-4150 5650);
FORCEPROP 0 LAST $SEC 1
J 0
(-3750 5750);
DISPLAY 0.680851 (-3750 5750);
PAINT MONO (-3750 5750);
DISPLAY INVISIBLE (-3750 5750);
FORCEPROP 0 LAST CDS_SEC 1
J 0
(-3750 5750);
DISPLAY 1.021277 (-3750 5750);
DISPLAY INVISIBLE (-3750 5750);
FORCEPROP 0 LASTPIN (-4100 5650) $PN 1
J 2
(-4110 5660);
DISPLAY 0.680851 (-4110 5660);
PAINT MONO (-4110 5660);
FORCEPROP 0 LASTPIN (-3850 5650) $PN 2
J 0
(-3840 5660);
DISPLAY 0.680851 (-3840 5660);
PAINT MONO (-3840 5660);
FORCEPROP 1 LAST VALUE 0.1UF
J 0
(-3750 5650);
DISPLAY 1.212766 (-3750 5650);
PAINT GREEN (-3750 5650);
FORCEPROP 0 LAST PACKAGE 0402
J 0
(-3450 5650);
DISPLAY 1.021277 (-3450 5650);
FORCEPROP 1 LAST TOLERANCE 10%
J 2
(-4100 5750);
DISPLAY 1.212766 (-4100 5750);
PAINT GREEN (-4100 5750);
DISPLAY INVISIBLE (-4100 5750);
FORCEPROP 2 LAST SIGNAL_MODEL DEFAULT_CAPACITOR_100000pF_1_2
J 0
(-4050 5850);
DISPLAY 1.021277 (-4050 5850);
DISPLAY INVISIBLE (-4050 5850);
FORCEPROP 1 LAST CLS_PN G105-0B104-CK
J 2
(-4050 5750);
DISPLAY 1.212766 (-4050 5750);
PAINT GREEN (-4050 5750);
DISPLAY INVISIBLE (-4050 5750);
FORCEPROP 1 LAST CDS_LMAN_SYM_OUTLINE 0,50,50,-50
J 0
(-4000 5650);
DISPLAY 0.468085 (-4000 5650);
PAINT GREEN (-4000 5650);
DISPLAY INVISIBLE (-4000 5650);
FORCEPROP 2 LAST CDS_LIB passive
J 0
(-4000 5650);
DISPLAY INVISIBLE (-4000 5650);
FORCEPROP 1 LAST PATH I118
J 2
(-4050 5750);
DISPLAY 1.212766 (-4050 5750);
PAINT GREEN (-4050 5750);
DISPLAY INVISIBLE (-4050 5750);
FORCEADD CAPACITOR..1
(-4000 5550);
FORCEPROP 1 LAST LOCATION C34
J 2
(-4150 5550);
DISPLAY 1.212766 (-4150 5550);
PAINT GREEN (-4150 5550);
FORCEPROP 0 LAST $SEC 1
J 0
(-3750 5650);
DISPLAY 0.680851 (-3750 5650);
PAINT MONO (-3750 5650);
DISPLAY INVISIBLE (-3750 5650);
FORCEPROP 0 LAST CDS_SEC 1
J 0
(-3750 5650);
DISPLAY 1.021277 (-3750 5650);
DISPLAY INVISIBLE (-3750 5650);
FORCEPROP 0 LASTPIN (-4100 5550) $PN 1
J 2
(-4110 5560);
DISPLAY 0.680851 (-4110 5560);
PAINT MONO (-4110 5560);
FORCEPROP 0 LASTPIN (-3850 5550) $PN 2
J 0
(-3840 5560);
DISPLAY 0.680851 (-3840 5560);
PAINT MONO (-3840 5560);
FORCEPROP 0 LAST PACKAGE 0402
J 0
(-3450 5550);
DISPLAY 1.021277 (-3450 5550);
FORCEPROP 1 LAST VALUE 0.1UF
J 0
(-3750 5550);
DISPLAY 1.212766 (-3750 5550);
PAINT GREEN (-3750 5550);
FORCEPROP 1 LAST TOLERANCE 10%
J 2
(-4100 5650);
DISPLAY 1.212766 (-4100 5650);
PAINT GREEN (-4100 5650);
DISPLAY INVISIBLE (-4100 5650);
FORCEPROP 2 LAST SIGNAL_MODEL DEFAULT_CAPACITOR_100000pF_1_2
J 0
(-4050 5750);
DISPLAY 1.021277 (-4050 5750);
DISPLAY INVISIBLE (-4050 5750);
FORCEPROP 1 LAST CLS_PN G105-0B104-CK
J 2
(-4050 5650);
DISPLAY 1.212766 (-4050 5650);
PAINT GREEN (-4050 5650);
DISPLAY INVISIBLE (-4050 5650);
FORCEPROP 1 LAST CDS_LMAN_SYM_OUTLINE 0,50,50,-50
J 0
(-4000 5550);
DISPLAY 0.468085 (-4000 5550);
PAINT GREEN (-4000 5550);
DISPLAY INVISIBLE (-4000 5550);
FORCEPROP 2 LAST CDS_LIB passive
J 0
(-4000 5550);
DISPLAY INVISIBLE (-4000 5550);
FORCEPROP 1 LAST PATH I119
J 2
(-4050 5650);
DISPLAY 1.212766 (-4050 5650);
PAINT GREEN (-4050 5650);
DISPLAY INVISIBLE (-4050 5650);
FORCEADD OFFPAGE_IN..1
(-9650 6450);
FORCEPROP 2 LAST $XR0 9D8< 
J 0
(-9802 6450);
DISPLAY 0.638298 (-9802 6450);
PAINT MONO (-9802 6450);
FORCEPROP 2 LAST $XR1 9G3< 
J 0
(-9952 6450);
DISPLAY 0.638298 (-9952 6450);
PAINT MONO (-9952 6450);
FORCEPROP 1 LAST BODY_TYPE COMMENT
J 0
(-9640 6585);
DISPLAY 0.808511 (-9640 6585);
PAINT GREEN (-9640 6585);
DISPLAY INVISIBLE (-9640 6585);
FORCEPROP 1 LAST CDS_LMAN_SYM_OUTLINE -50,50,50,-50
J 0
(-9650 6450);
DISPLAY 0.468085 (-9650 6450);
PAINT GREEN (-9650 6450);
DISPLAY INVISIBLE (-9650 6450);
FORCEPROP 2 LAST CDS_LIB cls
J 0
(-9650 6450);
DISPLAY INVISIBLE (-9650 6450);
FORCEPROP 1 LAST OFFPAGE TRUE
J 0
(-9640 6505);
DISPLAY 0.808511 (-9640 6505);
PAINT GREEN (-9640 6505);
DISPLAY INVISIBLE (-9640 6505);
FORCEPROP 2 LAST PATH I12
J 0
(-9800 6500);
DISPLAY 1.021277 (-9800 6500);
DISPLAY INVISIBLE (-9800 6500);
FORCEADD CAPACITOR..1
(-4000 5250);
FORCEPROP 1 LAST LOCATION C35
J 2
(-4150 5250);
DISPLAY 1.212766 (-4150 5250);
PAINT GREEN (-4150 5250);
FORCEPROP 0 LAST $SEC 1
J 0
(-3750 5350);
DISPLAY 0.680851 (-3750 5350);
PAINT MONO (-3750 5350);
DISPLAY INVISIBLE (-3750 5350);
FORCEPROP 0 LAST CDS_SEC 1
J 0
(-3750 5350);
DISPLAY 1.021277 (-3750 5350);
DISPLAY INVISIBLE (-3750 5350);
FORCEPROP 0 LASTPIN (-4100 5250) $PN 1
J 2
(-4110 5260);
DISPLAY 0.680851 (-4110 5260);
PAINT MONO (-4110 5260);
FORCEPROP 0 LASTPIN (-3850 5250) $PN 2
J 0
(-3840 5260);
DISPLAY 0.680851 (-3840 5260);
PAINT MONO (-3840 5260);
FORCEPROP 1 LAST VALUE 0.1UF
J 0
(-3750 5250);
DISPLAY 1.212766 (-3750 5250);
PAINT GREEN (-3750 5250);
FORCEPROP 0 LAST PACKAGE 0402
J 0
(-3450 5250);
DISPLAY 1.021277 (-3450 5250);
FORCEPROP 1 LAST TOLERANCE 10%
J 2
(-4100 5350);
DISPLAY 1.212766 (-4100 5350);
PAINT GREEN (-4100 5350);
DISPLAY INVISIBLE (-4100 5350);
FORCEPROP 2 LAST SIGNAL_MODEL DEFAULT_CAPACITOR_100000pF_1_2
J 0
(-4050 5450);
DISPLAY 1.021277 (-4050 5450);
DISPLAY INVISIBLE (-4050 5450);
FORCEPROP 1 LAST CLS_PN G105-0B104-CK
J 2
(-4050 5350);
DISPLAY 1.212766 (-4050 5350);
PAINT GREEN (-4050 5350);
DISPLAY INVISIBLE (-4050 5350);
FORCEPROP 1 LAST CDS_LMAN_SYM_OUTLINE 0,50,50,-50
J 0
(-4000 5250);
DISPLAY 0.468085 (-4000 5250);
PAINT GREEN (-4000 5250);
DISPLAY INVISIBLE (-4000 5250);
FORCEPROP 2 LAST CDS_LIB passive
J 0
(-4000 5250);
DISPLAY INVISIBLE (-4000 5250);
FORCEPROP 1 LAST PATH I120
J 2
(-4050 5350);
DISPLAY 1.212766 (-4050 5350);
PAINT GREEN (-4050 5350);
DISPLAY INVISIBLE (-4050 5350);
FORCEADD CAPACITOR..1
(-4000 5150);
FORCEPROP 1 LAST LOCATION C36
J 2
(-4150 5150);
DISPLAY 1.212766 (-4150 5150);
PAINT GREEN (-4150 5150);
FORCEPROP 0 LAST $SEC 1
J 0
(-3750 5250);
DISPLAY 0.680851 (-3750 5250);
PAINT MONO (-3750 5250);
DISPLAY INVISIBLE (-3750 5250);
FORCEPROP 0 LAST CDS_SEC 1
J 0
(-3750 5250);
DISPLAY 1.021277 (-3750 5250);
DISPLAY INVISIBLE (-3750 5250);
FORCEPROP 0 LASTPIN (-4100 5150) $PN 1
J 2
(-4110 5160);
DISPLAY 0.680851 (-4110 5160);
PAINT MONO (-4110 5160);
FORCEPROP 0 LASTPIN (-3850 5150) $PN 2
J 0
(-3840 5160);
DISPLAY 0.680851 (-3840 5160);
PAINT MONO (-3840 5160);
FORCEPROP 0 LAST PACKAGE 0402
J 0
(-3450 5150);
DISPLAY 1.021277 (-3450 5150);
FORCEPROP 1 LAST VALUE 0.1UF
J 0
(-3750 5150);
DISPLAY 1.212766 (-3750 5150);
PAINT GREEN (-3750 5150);
FORCEPROP 2 LAST CDS_LIB passive
J 0
(-4000 5150);
DISPLAY INVISIBLE (-4000 5150);
FORCEPROP 1 LAST CDS_LMAN_SYM_OUTLINE 0,50,50,-50
J 0
(-4000 5150);
DISPLAY 0.468085 (-4000 5150);
PAINT GREEN (-4000 5150);
DISPLAY INVISIBLE (-4000 5150);
FORCEPROP 1 LAST CLS_PN G105-0B104-CK
J 2
(-4050 5250);
DISPLAY 1.212766 (-4050 5250);
PAINT GREEN (-4050 5250);
DISPLAY INVISIBLE (-4050 5250);
FORCEPROP 2 LAST SIGNAL_MODEL DEFAULT_CAPACITOR_100000pF_1_2
J 0
(-4050 5350);
DISPLAY 1.021277 (-4050 5350);
DISPLAY INVISIBLE (-4050 5350);
FORCEPROP 1 LAST TOLERANCE 10%
J 2
(-4100 5250);
DISPLAY 1.212766 (-4100 5250);
PAINT GREEN (-4100 5250);
DISPLAY INVISIBLE (-4100 5250);
FORCEPROP 1 LAST PATH I121
J 2
(-4050 5250);
DISPLAY 1.212766 (-4050 5250);
PAINT GREEN (-4050 5250);
DISPLAY INVISIBLE (-4050 5250);
FORCEADD RESISTOR..1
(900 7150);
FORCEPROP 1 LAST $LOCATION R356
J 2
(750 7150);
DISPLAY 1.212766 (750 7150);
PAINT GREEN (750 7150);
FORCEPROP 0 LAST CDS_LOCATION R356
J 0
(1150 7250);
DISPLAY 1.021277 (1150 7250);
DISPLAY INVISIBLE (1150 7250);
FORCEPROP 0 LAST $SEC 1
J 0
(1150 7250);
DISPLAY 0.680851 (1150 7250);
PAINT MONO (1150 7250);
DISPLAY INVISIBLE (1150 7250);
FORCEPROP 0 LAST CDS_SEC 1
J 0
(1150 7250);
DISPLAY 1.021277 (1150 7250);
DISPLAY INVISIBLE (1150 7250);
FORCEPROP 0 LASTPIN (800 7150) $PN 1
J 2
(790 7160);
DISPLAY 0.680851 (790 7160);
PAINT MONO (790 7160);
FORCEPROP 0 LASTPIN (1050 7150) $PN 2
J 0
(1060 7160);
DISPLAY 0.680851 (1060 7160);
PAINT MONO (1060 7160);
FORCEPROP 1 LAST VALUE 0OHM
J 0
(1150 7150);
DISPLAY 1.212766 (1150 7150);
PAINT GREEN (1150 7150);
FORCEPROP 0 LAST PACKAGE 0402
J 0
(850 7200);
DISPLAY 0.808511 (850 7200);
FORCEPROP 1 LAST CDS_LMAN_SYM_OUTLINE -50,50,100,-50
J 0
(900 7150);
DISPLAY 0.468085 (900 7150);
PAINT GREEN (900 7150);
DISPLAY INVISIBLE (900 7150);
FORCEPROP 2 LAST CDS_LIB passive
J 0
(900 7150);
DISPLAY INVISIBLE (900 7150);
FORCEPROP 1 LAST CLS_PN G155-100R0-J0
J 0
(764 7350);
DISPLAY 1.212766 (764 7350);
PAINT GREEN (764 7350);
DISPLAY INVISIBLE (764 7350);
FORCEPROP 1 LAST TOLERANCE -
J 0
(703 7405);
DISPLAY 1.212766 (703 7405);
PAINT GREEN (703 7405);
DISPLAY INVISIBLE (703 7405);
FORCEPROP 1 LAST PATH I122
J 0
(703 7255);
DISPLAY 1.212766 (703 7255);
PAINT GREEN (703 7255);
DISPLAY INVISIBLE (703 7255);
FORCEADD OFFPAGE_OUT..1
(2300 7150);
FORCEPROP 2 LAST $XR0 25C9<> 
J 0
(2355 7150);
DISPLAY 0.638298 (2355 7150);
PAINT MONO (2355 7150);
FORCEPROP 2 LAST $XR1 10F5< 
J 0
(2550 7150);
DISPLAY 0.638298 (2550 7150);
PAINT MONO (2550 7150);
FORCEPROP 1 LAST BODY_TYPE COMMENT
J 0
(2310 7285);
DISPLAY 0.808511 (2310 7285);
PAINT GREEN (2310 7285);
DISPLAY INVISIBLE (2310 7285);
FORCEPROP 1 LAST CDS_LMAN_SYM_OUTLINE -50,50,50,-50
J 0
(2300 7150);
DISPLAY 0.468085 (2300 7150);
PAINT GREEN (2300 7150);
DISPLAY INVISIBLE (2300 7150);
FORCEPROP 2 LAST CDS_LIB cls
J 0
(2300 7150);
DISPLAY INVISIBLE (2300 7150);
FORCEPROP 1 LAST OFFPAGE TRUE
J 0
(2310 7205);
DISPLAY 0.808511 (2310 7205);
PAINT GREEN (2310 7205);
DISPLAY INVISIBLE (2310 7205);
FORCEPROP 2 LAST PATH I123
J 0
(2350 7250);
DISPLAY 1.021277 (2350 7250);
DISPLAY INVISIBLE (2350 7250);
FORCEADD CAPACITOR..2
R 2
(-5900 3900);
FORCEPROP 1 LAST $LOCATION C289
J 2
(-5650 3800);
DISPLAY 1.212766 (-5650 3800);
PAINT GREEN (-5650 3800);
FORCEPROP 0 LAST CDS_LOCATION C289
J 0
(-5800 4050);
DISPLAY 1.021277 (-5800 4050);
DISPLAY INVISIBLE (-5800 4050);
FORCEPROP 0 LAST $SEC 1
J 0
(-5800 4050);
DISPLAY 0.680851 (-5800 4050);
PAINT MONO (-5800 4050);
DISPLAY INVISIBLE (-5800 4050);
FORCEPROP 0 LAST CDS_SEC 1
J 0
(-5800 4050);
DISPLAY 1.021277 (-5800 4050);
DISPLAY INVISIBLE (-5800 4050);
FORCEPROP 0 LASTPIN (-5900 4000) $PN 1
R 1
J 0
(-5910 4010);
DISPLAY 0.680851 (-5910 4010);
PAINT MONO (-5910 4010);
FORCEPROP 0 LASTPIN (-5900 3750) $PN 2
R 1
J 2
(-5910 3740);
DISPLAY 0.680851 (-5910 3740);
PAINT MONO (-5910 3740);
FORCEPROP 1 LAST VALUE 10UF
J 2
(-5600 3900);
DISPLAY 1.212766 (-5600 3900);
PAINT GREEN (-5600 3900);
FORCEPROP 0 LAST PACKAGE 0402
J 0
(-5800 4000);
DISPLAY 1.021277 (-5800 4000);
FORCEPROP 0 LAST VOLTAGE 6.3V
J 0
(-5850 3700);
DISPLAY 1.021277 (-5850 3700);
FORCEPROP 1 LAST TOLERANCE 20%
J 2
(-5750 4000);
DISPLAY 1.212766 (-5750 4000);
PAINT GREEN (-5750 4000);
DISPLAY INVISIBLE (-5750 4000);
FORCEPROP 1 LAST CLS_PN G105-0C106-BM
J 2
(-5800 3950);
DISPLAY 1.212766 (-5800 3950);
PAINT GREEN (-5800 3950);
DISPLAY INVISIBLE (-5800 3950);
FORCEPROP 1 LAST CDS_LMAN_SYM_OUTLINE -50,0,50,-50
J 2
(-5900 3900);
DISPLAY 0.468085 (-5900 3900);
PAINT GREEN (-5900 3900);
DISPLAY INVISIBLE (-5900 3900);
FORCEPROP 2 LAST CDS_LIB passive
J 0
(-5900 3900);
DISPLAY INVISIBLE (-5900 3900);
FORCEPROP 1 LAST PATH I124
J 2
(-5800 3950);
DISPLAY 1.212766 (-5800 3950);
PAINT GREEN (-5800 3950);
DISPLAY INVISIBLE (-5800 3950);
FORCEADD GND_SG..1
R 2
(-5850 3500);
FORCEPROP 3 LASTPIN (-5900 3550) SIG_NAME SG\g
J 0
(-5890 3560);
DISPLAY 0.659574 (-5890 3560);
PAINT MONO (-5890 3560);
DISPLAY INVISIBLE (-5890 3560);
FORCEPROP 1 LAST HDL_POWER SG
J 1
(-5905 3405);
DISPLAY 0.808511 (-5905 3405);
PAINT GREEN (-5905 3405);
FORCEPROP 1 LAST CDS_LMAN_SYM_OUTLINE 0,0,100,-50
J 2
(-5850 3500);
DISPLAY 0.468085 (-5850 3500);
PAINT GREEN (-5850 3500);
DISPLAY INVISIBLE (-5850 3500);
FORCEPROP 2 LAST CDS_LIB cls
J 0
(-5850 3500);
DISPLAY INVISIBLE (-5850 3500);
FORCEPROP 1 LAST BODY_TYPE PLUMBING
J 2
(-5865 3485);
DISPLAY 0.808511 (-5865 3485);
PAINT GREEN (-5865 3485);
DISPLAY INVISIBLE (-5865 3485);
FORCEPROP 1 LAST PATH I125
J 2
(-5885 3500);
DISPLAY 0.808511 (-5885 3500);
PAINT GREEN (-5885 3500);
DISPLAY INVISIBLE (-5885 3500);
FORCEADD CAPACITOR..2
R 2
(-5500 3900);
FORCEPROP 1 LAST $LOCATION C290
J 2
(-5250 3800);
DISPLAY 1.212766 (-5250 3800);
PAINT GREEN (-5250 3800);
FORCEPROP 0 LAST CDS_LOCATION C290
J 0
(-5350 4050);
DISPLAY 1.021277 (-5350 4050);
DISPLAY INVISIBLE (-5350 4050);
FORCEPROP 0 LAST $SEC 1
J 0
(-5350 4050);
DISPLAY 0.680851 (-5350 4050);
PAINT MONO (-5350 4050);
DISPLAY INVISIBLE (-5350 4050);
FORCEPROP 0 LAST CDS_SEC 1
J 0
(-5350 4050);
DISPLAY 1.021277 (-5350 4050);
DISPLAY INVISIBLE (-5350 4050);
FORCEPROP 0 LASTPIN (-5500 4000) $PN 1
R 1
J 0
(-5510 4010);
DISPLAY 0.680851 (-5510 4010);
PAINT MONO (-5510 4010);
FORCEPROP 0 LASTPIN (-5500 3750) $PN 2
R 1
J 2
(-5510 3740);
DISPLAY 0.680851 (-5510 3740);
PAINT MONO (-5510 3740);
FORCEPROP 0 LAST VOLTAGE 25V
J 0
(-5400 3700);
DISPLAY 1.021277 (-5400 3700);
FORCEPROP 0 LAST PACKAGE 0402
J 0
(-5350 4000);
DISPLAY 1.021277 (-5350 4000);
FORCEPROP 1 LAST VALUE 0.1UF
J 2
(-5100 3900);
DISPLAY 1.212766 (-5100 3900);
PAINT GREEN (-5100 3900);
FORCEPROP 1 LAST TOLERANCE 10%
J 2
(-5350 4000);
DISPLAY 1.212766 (-5350 4000);
PAINT GREEN (-5350 4000);
DISPLAY INVISIBLE (-5350 4000);
FORCEPROP 1 LAST CLS_PN G105-0B104-EK
J 2
(-5400 3950);
DISPLAY 1.212766 (-5400 3950);
PAINT GREEN (-5400 3950);
DISPLAY INVISIBLE (-5400 3950);
FORCEPROP 1 LAST PATH I126
J 2
(-5400 3950);
DISPLAY 1.212766 (-5400 3950);
PAINT GREEN (-5400 3950);
DISPLAY INVISIBLE (-5400 3950);
FORCEPROP 2 LAST CDS_LIB passive
J 0
(-5500 3900);
DISPLAY INVISIBLE (-5500 3900);
FORCEPROP 1 LAST CDS_LMAN_SYM_OUTLINE -50,0,50,-50
J 2
(-5500 3900);
DISPLAY 0.468085 (-5500 3900);
PAINT GREEN (-5500 3900);
DISPLAY INVISIBLE (-5500 3900);
FORCEADD CAPACITOR..2
R 2
(-6650 3900);
FORCEPROP 1 LAST $LOCATION C288
J 2
(-6400 3800);
DISPLAY 1.212766 (-6400 3800);
PAINT GREEN (-6400 3800);
FORCEPROP 0 LAST CDS_LOCATION C288
J 0
(-6500 4050);
DISPLAY 1.021277 (-6500 4050);
DISPLAY INVISIBLE (-6500 4050);
FORCEPROP 0 LAST $SEC 1
J 0
(-6500 4050);
DISPLAY 0.680851 (-6500 4050);
PAINT MONO (-6500 4050);
DISPLAY INVISIBLE (-6500 4050);
FORCEPROP 0 LAST CDS_SEC 1
J 0
(-6500 4050);
DISPLAY 1.021277 (-6500 4050);
DISPLAY INVISIBLE (-6500 4050);
FORCEPROP 0 LASTPIN (-6650 4000) $PN 1
R 1
J 0
(-6660 4010);
DISPLAY 0.680851 (-6660 4010);
PAINT MONO (-6660 4010);
FORCEPROP 0 LASTPIN (-6650 3750) $PN 2
R 1
J 2
(-6660 3740);
DISPLAY 0.680851 (-6660 3740);
PAINT MONO (-6660 3740);
FORCEPROP 0 LAST PACKAGE 0402
J 0
(-6550 4000);
DISPLAY 1.021277 (-6550 4000);
FORCEPROP 1 LAST VALUE 0.1UF
J 2
(-6250 3900);
DISPLAY 1.212766 (-6250 3900);
PAINT GREEN (-6250 3900);
FORCEPROP 0 LAST VOLTAGE 25V
J 0
(-6550 3700);
DISPLAY 1.021277 (-6550 3700);
FORCEPROP 2 LAST CDS_LIB passive
J 0
(-6650 3900);
DISPLAY INVISIBLE (-6650 3900);
FORCEPROP 1 LAST CDS_LMAN_SYM_OUTLINE -50,0,50,-50
J 2
(-6650 3900);
DISPLAY 0.468085 (-6650 3900);
PAINT GREEN (-6650 3900);
DISPLAY INVISIBLE (-6650 3900);
FORCEPROP 1 LAST TOLERANCE 10%
J 2
(-6500 4000);
DISPLAY 1.212766 (-6500 4000);
PAINT GREEN (-6500 4000);
DISPLAY INVISIBLE (-6500 4000);
FORCEPROP 1 LAST CLS_PN G105-0B104-EK
J 2
(-6550 3950);
DISPLAY 1.212766 (-6550 3950);
PAINT GREEN (-6550 3950);
DISPLAY INVISIBLE (-6550 3950);
FORCEPROP 1 LAST PATH I127
J 2
(-6550 3950);
DISPLAY 1.212766 (-6550 3950);
PAINT GREEN (-6550 3950);
DISPLAY INVISIBLE (-6550 3950);
FORCEADD GND_SG..1
R 2
(-7000 3500);
FORCEPROP 3 LASTPIN (-7050 3550) SIG_NAME SG\g
J 0
(-7040 3560);
DISPLAY 0.659574 (-7040 3560);
PAINT MONO (-7040 3560);
DISPLAY INVISIBLE (-7040 3560);
FORCEPROP 1 LAST HDL_POWER SG
J 1
(-7055 3405);
DISPLAY 0.808511 (-7055 3405);
PAINT GREEN (-7055 3405);
FORCEPROP 2 LAST CDS_LIB cls
J 0
(-7000 3500);
DISPLAY INVISIBLE (-7000 3500);
FORCEPROP 1 LAST CDS_LMAN_SYM_OUTLINE 0,0,100,-50
J 2
(-7000 3500);
DISPLAY 0.468085 (-7000 3500);
PAINT GREEN (-7000 3500);
DISPLAY INVISIBLE (-7000 3500);
FORCEPROP 1 LAST BODY_TYPE PLUMBING
J 2
(-7015 3485);
DISPLAY 0.808511 (-7015 3485);
PAINT GREEN (-7015 3485);
DISPLAY INVISIBLE (-7015 3485);
FORCEPROP 1 LAST PATH I128
J 2
(-7035 3500);
DISPLAY 0.808511 (-7035 3500);
PAINT GREEN (-7035 3500);
DISPLAY INVISIBLE (-7035 3500);
FORCEADD CAPACITOR..2
R 2
(-7050 3900);
FORCEPROP 1 LAST $LOCATION C287
J 2
(-6800 3800);
DISPLAY 1.212766 (-6800 3800);
PAINT GREEN (-6800 3800);
FORCEPROP 0 LAST CDS_LOCATION C287
J 0
(-6950 4050);
DISPLAY 1.021277 (-6950 4050);
DISPLAY INVISIBLE (-6950 4050);
FORCEPROP 0 LAST $SEC 1
J 0
(-6950 4050);
DISPLAY 0.680851 (-6950 4050);
PAINT MONO (-6950 4050);
DISPLAY INVISIBLE (-6950 4050);
FORCEPROP 0 LAST CDS_SEC 1
J 0
(-6950 4050);
DISPLAY 1.021277 (-6950 4050);
DISPLAY INVISIBLE (-6950 4050);
FORCEPROP 0 LASTPIN (-7050 4000) $PN 1
R 1
J 0
(-7060 4010);
DISPLAY 0.680851 (-7060 4010);
PAINT MONO (-7060 4010);
FORCEPROP 0 LASTPIN (-7050 3750) $PN 2
R 1
J 2
(-7060 3740);
DISPLAY 0.680851 (-7060 3740);
PAINT MONO (-7060 3740);
FORCEPROP 1 LAST VALUE 10UF
J 2
(-6750 3900);
DISPLAY 1.212766 (-6750 3900);
PAINT GREEN (-6750 3900);
FORCEPROP 0 LAST PACKAGE 0402
J 0
(-6950 4000);
DISPLAY 1.021277 (-6950 4000);
FORCEPROP 0 LAST VOLTAGE 6.3V
J 0
(-7000 3700);
DISPLAY 1.021277 (-7000 3700);
FORCEPROP 2 LAST CDS_LIB passive
J 0
(-7050 3900);
DISPLAY INVISIBLE (-7050 3900);
FORCEPROP 1 LAST CDS_LMAN_SYM_OUTLINE -50,0,50,-50
J 2
(-7050 3900);
DISPLAY 0.468085 (-7050 3900);
PAINT GREEN (-7050 3900);
DISPLAY INVISIBLE (-7050 3900);
FORCEPROP 1 LAST CLS_PN G105-0C106-BM
J 2
(-6950 3950);
DISPLAY 1.212766 (-6950 3950);
PAINT GREEN (-6950 3950);
DISPLAY INVISIBLE (-6950 3950);
FORCEPROP 1 LAST TOLERANCE 20%
J 2
(-6900 4000);
DISPLAY 1.212766 (-6900 4000);
PAINT GREEN (-6900 4000);
DISPLAY INVISIBLE (-6900 4000);
FORCEPROP 1 LAST PATH I129
J 2
(-6950 3950);
DISPLAY 1.212766 (-6950 3950);
PAINT GREEN (-6950 3950);
DISPLAY INVISIBLE (-6950 3950);
FORCEADD OFFPAGE_OUT..1
R 2
(-9650 6750);
FORCEPROP 2 LAST $XR0 10C5< 
J 0
(-9833 6750);
DISPLAY 0.638298 (-9833 6750);
PAINT MONO (-9833 6750);
FORCEPROP 1 LAST BODY_TYPE COMMENT
J 2
(-9660 6885);
DISPLAY 0.808511 (-9660 6885);
PAINT GREEN (-9660 6885);
DISPLAY INVISIBLE (-9660 6885);
FORCEPROP 1 LAST CDS_LMAN_SYM_OUTLINE -50,50,50,-50
J 2
(-9650 6750);
DISPLAY 0.468085 (-9650 6750);
PAINT GREEN (-9650 6750);
DISPLAY INVISIBLE (-9650 6750);
FORCEPROP 2 LAST CDS_LIB cls
J 0
(-9650 6750);
DISPLAY INVISIBLE (-9650 6750);
FORCEPROP 1 LAST OFFPAGE TRUE
J 2
(-9660 6805);
DISPLAY 0.808511 (-9660 6805);
PAINT GREEN (-9660 6805);
DISPLAY INVISIBLE (-9660 6805);
FORCEPROP 2 LAST PATH I13
J 0
(-9800 6800);
DISPLAY 1.021277 (-9800 6800);
DISPLAY INVISIBLE (-9800 6800);
FORCEADD VCC..1
(-5950 4250);
FORCEPROP 3 LASTPIN (-5900 4200) SIG_NAME XP3R3V_PCIE\g
J 0
(-5890 4210);
DISPLAY 0.659574 (-5890 4210);
PAINT MONO (-5890 4210);
DISPLAY INVISIBLE (-5890 4210);
FORCEPROP 1 LAST HDL_POWER XP3R3V_PCIE
J 1
(-5900 4300);
DISPLAY 0.808511 (-5900 4300);
PAINT GREEN (-5900 4300);
FORCEPROP 0 LAST VOLTAGE 3.3
J 1
(-5900 4350);
DISPLAY 1.021277 (-5900 4350);
DISPLAY BOTH (-5900 4350);
FORCEPROP 2 LAST CDS_LIB cls
J 0
(-5950 4250);
DISPLAY INVISIBLE (-5950 4250);
FORCEPROP 1 LAST CDS_LMAN_SYM_OUTLINE -250,250,250,-250
J 0
(-5950 4250);
DISPLAY 0.468085 (-5950 4250);
PAINT GREEN (-5950 4250);
DISPLAY INVISIBLE (-5950 4250);
FORCEPROP 1 LAST BODY_TYPE PLUMBING
J 0
(-5995 4207);
DISPLAY 0.340426 (-5995 4207);
PAINT GREEN (-5995 4207);
DISPLAY INVISIBLE (-5995 4207);
FORCEPROP 1 LAST PATH I130
J 0
(-5915 4340);
DISPLAY 0.808511 (-5915 4340);
PAINT GREEN (-5915 4340);
DISPLAY INVISIBLE (-5915 4340);
FORCEADD VCC..1
(-7100 4200);
FORCEPROP 3 LASTPIN (-7050 4150) SIG_NAME XP3R3V_AUX_PCIE\g
J 0
(-7040 4160);
DISPLAY 0.659574 (-7040 4160);
PAINT MONO (-7040 4160);
DISPLAY INVISIBLE (-7040 4160);
FORCEPROP 1 LAST HDL_POWER XP3R3V_AUX_PCIE
J 1
(-7050 4250);
DISPLAY 0.808511 (-7050 4250);
PAINT GREEN (-7050 4250);
FORCEPROP 0 LAST VOLTAGE 3.3
J 1
(-7050 4300);
DISPLAY 1.021277 (-7050 4300);
DISPLAY BOTH (-7050 4300);
FORCEPROP 1 LAST CDS_LMAN_SYM_OUTLINE -250,250,250,-250
J 0
(-7100 4200);
DISPLAY 0.468085 (-7100 4200);
PAINT GREEN (-7100 4200);
DISPLAY INVISIBLE (-7100 4200);
FORCEPROP 2 LAST CDS_LIB cls
J 0
(-7100 4200);
DISPLAY INVISIBLE (-7100 4200);
FORCEPROP 1 LAST BODY_TYPE PLUMBING
J 0
(-7145 4157);
DISPLAY 0.340426 (-7145 4157);
PAINT GREEN (-7145 4157);
DISPLAY INVISIBLE (-7145 4157);
FORCEPROP 1 LAST PATH I131
J 0
(-7065 4290);
DISPLAY 0.808511 (-7065 4290);
PAINT GREEN (-7065 4290);
DISPLAY INVISIBLE (-7065 4290);
FORCEADD FERRITEBEAD..1
(-5150 4150);
FORCEPROP 1 LAST $LOCATION L21
J 2
(-5200 4150);
DISPLAY 1.212766 (-5200 4150);
PAINT GREEN (-5200 4150);
FORCEPROP 0 LAST CDS_LOCATION L21
J 0
(-5300 4300);
DISPLAY 1.021277 (-5300 4300);
DISPLAY INVISIBLE (-5300 4300);
FORCEPROP 0 LAST $SEC 1
J 0
(-5300 4300);
DISPLAY 0.680851 (-5300 4300);
PAINT MONO (-5300 4300);
DISPLAY INVISIBLE (-5300 4300);
FORCEPROP 0 LAST CDS_SEC 1
J 0
(-5300 4300);
DISPLAY 1.021277 (-5300 4300);
DISPLAY INVISIBLE (-5300 4300);
FORCEPROP 0 LASTPIN (-5250 4100) $PN 1
J 2
(-5260 4110);
DISPLAY 0.680851 (-5260 4110);
PAINT MONO (-5260 4110);
FORCEPROP 0 LASTPIN (-4850 4100) $PN 2
J 0
(-4840 4110);
DISPLAY 0.680851 (-4840 4110);
PAINT MONO (-4840 4110);
FORCEPROP 0 LAST NO_ASSY TRUE
J 0
(-5300 4250);
DISPLAY 1.021277 (-5300 4250);
DISPLAY BOTH (-5300 4250);
FORCEPROP 0 LAST PACKAGE 0603
J 0
(-5150 4150);
DISPLAY 1.021277 (-5150 4150);
FORCEPROP 1 LAST VALUE 26OHM
J 0
(-4800 4100);
DISPLAY 1.212766 (-4800 4100);
PAINT GREEN (-4800 4100);
FORCEPROP 1 LAST CLS_PN G191-10101-01
J 2
(-5200 4200);
DISPLAY 1.212766 (-5200 4200);
PAINT GREEN (-5200 4200);
DISPLAY INVISIBLE (-5200 4200);
FORCEPROP 1 LAST TOLERANCE 25%
J 0
(-5250 4200);
DISPLAY 1.212766 (-5250 4200);
PAINT GREEN (-5250 4200);
DISPLAY INVISIBLE (-5250 4200);
FORCEPROP 1 LAST PATH I132
J 2
(-5200 4200);
DISPLAY 1.212766 (-5200 4200);
PAINT GREEN (-5200 4200);
DISPLAY INVISIBLE (-5200 4200);
FORCEPROP 1 LAST CDS_LMAN_SYM_OUTLINE 0,0,200,-100
J 0
(-5150 4150);
DISPLAY 0.468085 (-5150 4150);
PAINT GREEN (-5150 4150);
DISPLAY INVISIBLE (-5150 4150);
FORCEPROP 2 LAST CDS_LIB passive
J 0
(-5150 4150);
DISPLAY INVISIBLE (-5150 4150);
FORCEADD VCC..1
(-4500 4300);
FORCEPROP 3 LASTPIN (-4450 4250) SIG_NAME XP3R3V\g
J 0
(-4440 4260);
DISPLAY 0.659574 (-4440 4260);
PAINT MONO (-4440 4260);
DISPLAY INVISIBLE (-4440 4260);
FORCEPROP 0 LAST VOLTAGE 3.3
J 0
(-4650 4400);
DISPLAY 0.808511 (-4650 4400);
DISPLAY BOTH (-4650 4400);
FORCEPROP 1 LAST HDL_POWER XP3R3V
J 1
(-4450 4350);
DISPLAY 0.808511 (-4450 4350);
PAINT GREEN (-4450 4350);
FORCEPROP 2 LAST CDS_LIB cls
J 0
(-4500 4300);
DISPLAY INVISIBLE (-4500 4300);
FORCEPROP 1 LAST CDS_LMAN_SYM_OUTLINE -250,250,250,-250
J 0
(-4500 4300);
DISPLAY 0.468085 (-4500 4300);
PAINT GREEN (-4500 4300);
DISPLAY INVISIBLE (-4500 4300);
FORCEPROP 1 LAST BODY_TYPE PLUMBING
J 0
(-4545 4257);
DISPLAY 0.340426 (-4545 4257);
PAINT GREEN (-4545 4257);
DISPLAY INVISIBLE (-4545 4257);
FORCEPROP 1 LAST PATH I133
J 0
(-4465 4390);
DISPLAY 0.808511 (-4465 4390);
PAINT GREEN (-4465 4390);
DISPLAY INVISIBLE (-4465 4390);
FORCEADD 74LVC1G07_SC70_5..1
(-900 7300);
FORCEPROP 1 LAST LOCATION U3
J 0
(-900 7350);
DISPLAY 1.212766 (-900 7350);
PAINT GREEN (-900 7350);
FORCEPROP 0 LAST $SEC 1
J 0
(-900 7600);
DISPLAY 0.680851 (-900 7600);
PAINT MONO (-900 7600);
DISPLAY INVISIBLE (-900 7600);
FORCEPROP 0 LAST CDS_SEC 1
J 0
(-900 7600);
DISPLAY 1.021277 (-900 7600);
DISPLAY INVISIBLE (-900 7600);
FORCEPROP 0 LASTPIN (-1000 7150) $PN 2
J 2
(-1010 7160);
DISPLAY 0.680851 (-1010 7160);
PAINT MONO (-1010 7160);
FORCEPROP 0 LASTPIN (-1000 6950) $PN 1
J 2
(-1010 6960);
DISPLAY 0.680851 (-1010 6960);
PAINT MONO (-1010 6960);
FORCEPROP 0 LASTPIN (-450 7150) $PN 4
J 0
(-440 7160);
DISPLAY 0.680851 (-440 7160);
PAINT MONO (-440 7160);
FORCEPROP 1 LAST CLS_PN G220-10017-01
J 0
(-900 7450);
DISPLAY 1.212766 (-900 7450);
PAINT GREEN (-900 7450);
FORCEPROP 0 LAST PART_NUMBER SN74LVC1G07DCKRG4
J 0
(-900 7550);
DISPLAY 1.021277 (-900 7550);
FORCEPROP 2 LAST CDS_LIB stdlogic
J 0
(-900 7300);
DISPLAY INVISIBLE (-900 7300);
FORCEPROP 1 LAST CDS_LMAN_SYM_OUTLINE 0,0,350,-450
J 0
(-900 7300);
DISPLAY 0.468085 (-900 7300);
PAINT GREEN (-900 7300);
DISPLAY INVISIBLE (-900 7300);
FORCEPROP 1 LAST PATH I134
J 0
(-900 7350);
DISPLAY 1.212766 (-900 7350);
PAINT GREEN (-900 7350);
DISPLAY INVISIBLE (-900 7350);
FORCEADD 74LVC1G07_SC70_5..2
(-900 6000);
FORCEPROP 1 LAST LOCATION U3
J 2
(-400 5200);
DISPLAY 1.212766 (-400 5200);
PAINT GREEN (-400 5200);
FORCEPROP 0 LAST $SEC 2
J 0
(-400 5300);
DISPLAY 0.680851 (-400 5300);
PAINT MONO (-400 5300);
DISPLAY INVISIBLE (-400 5300);
FORCEPROP 0 LAST CDS_SEC 2
J 0
(-400 5300);
DISPLAY 1.021277 (-400 5300);
DISPLAY INVISIBLE (-400 5300);
FORCEPROP 0 LASTPIN (-700 5400) $PN 3
R 1
J 2
(-710 5390);
DISPLAY 0.680851 (-710 5390);
PAINT MONO (-710 5390);
FORCEPROP 0 LASTPIN (-700 6100) $PN 5
R 1
J 0
(-710 6110);
DISPLAY 0.680851 (-710 6110);
PAINT MONO (-710 6110);
FORCEPROP 1 LAST CLS_PN G220-10017-01
J 2
(250 5000);
DISPLAY 1.212766 (250 5000);
PAINT GREEN (250 5000);
FORCEPROP 0 LAST PART_NUMBER SN74LVC1G07DCKRG4
J 0
(-500 5100);
DISPLAY 1.021277 (-500 5100);
FORCEPROP 2 LAST CDS_LIB stdlogic
J 0
(-900 6000);
DISPLAY INVISIBLE (-900 6000);
FORCEPROP 1 LAST CDS_LMAN_SYM_OUTLINE 0,0,400,-500
J 0
(-900 6000);
DISPLAY 0.468085 (-900 6000);
PAINT GREEN (-900 6000);
DISPLAY INVISIBLE (-900 6000);
FORCEPROP 1 LAST PATH I135
J 2
(-950 6050);
DISPLAY 1.212766 (-950 6050);
PAINT GREEN (-950 6050);
DISPLAY INVISIBLE (-950 6050);
FORCEADD OFFPAGE_IN..1
(-1450 7050);
FORCEPROP 2 LAST $XR0 25C9<> 
J 0
(-1664 7050);
DISPLAY 0.638298 (-1664 7050);
PAINT MONO (-1664 7050);
FORCEPROP 1 LAST BODY_TYPE COMMENT
J 0
(-1440 7185);
DISPLAY 0.808511 (-1440 7185);
PAINT GREEN (-1440 7185);
DISPLAY INVISIBLE (-1440 7185);
FORCEPROP 1 LAST OFFPAGE TRUE
J 0
(-1440 7105);
DISPLAY 0.808511 (-1440 7105);
PAINT GREEN (-1440 7105);
DISPLAY INVISIBLE (-1440 7105);
FORCEPROP 2 LAST PATH I138
J 0
(-1400 7150);
DISPLAY 1.021277 (-1400 7150);
DISPLAY INVISIBLE (-1400 7150);
FORCEPROP 2 LAST CDS_LIB cls
J 0
(-1450 7050);
DISPLAY INVISIBLE (-1450 7050);
FORCEPROP 1 LAST CDS_LMAN_SYM_OUTLINE -50,50,50,-50
J 0
(-1450 7050);
DISPLAY 0.468085 (-1450 7050);
PAINT GREEN (-1450 7050);
DISPLAY INVISIBLE (-1450 7050);
FORCEADD TPS3808G18DBVR_SOT23_6..1
(-450 3750);
FORCEPROP 1 LAST $LOCATION U34
J 0
(-450 3800);
DISPLAY 1.212766 (-450 3800);
PAINT GREEN (-450 3800);
FORCEPROP 0 LAST CDS_LOCATION U34
J 0
(-450 3900);
PAINT MONO (-450 3900);
DISPLAY INVISIBLE (-450 3900);
FORCEPROP 0 LAST $SEC 1
J 0
(-450 3900);
PAINT MONO (-450 3900);
DISPLAY INVISIBLE (-450 3900);
FORCEPROP 0 LAST CDS_SEC 1
J 0
(-450 3900);
PAINT MONO (-450 3900);
DISPLAY INVISIBLE (-450 3900);
FORCEPROP 0 LASTPIN (350 3450) $PN 4
J 0
(360 3460);
DISPLAY 0.808511 (360 3460);
PAINT MONO (360 3460);
FORCEPROP 0 LASTPIN (350 3250) $PN 2
J 0
(360 3260);
DISPLAY 0.808511 (360 3260);
PAINT MONO (360 3260);
FORCEPROP 0 LASTPIN (-550 3250) $PN 3
J 2
(-560 3260);
DISPLAY 0.808511 (-560 3260);
PAINT MONO (-560 3260);
FORCEPROP 0 LASTPIN (350 3650) $PN 1
J 0
(360 3660);
DISPLAY 0.808511 (360 3660);
PAINT MONO (360 3660);
FORCEPROP 0 LASTPIN (-550 3450) $PN 5
J 2
(-560 3460);
DISPLAY 0.808511 (-560 3460);
PAINT MONO (-560 3460);
FORCEPROP 0 LASTPIN (-550 3650) $PN 6
J 2
(-560 3660);
DISPLAY 0.808511 (-560 3660);
PAINT MONO (-560 3660);
FORCEPROP 1 LAST CLS_PN G222-00082-01
J 0
(-450 2900);
DISPLAY 1.212766 (-450 2900);
PAINT GREEN (-450 2900);
FORCEPROP 0 LAST PART_NUMBER TPS3808G33DBVRG4
J 0
(-450 3000);
DISPLAY 1.021277 (-450 3000);
FORCEPROP 1 LAST PATH I139
J 0
(-400 3800);
DISPLAY 1.212766 (-400 3800);
PAINT GREEN (-400 3800);
DISPLAY INVISIBLE (-400 3800);
FORCEPROP 1 LAST CDS_LMAN_SYM_OUTLINE 0,0,700,-600
J 0
(-450 3750);
DISPLAY 0.468085 (-450 3750);
PAINT GREEN (-450 3750);
DISPLAY INVISIBLE (-450 3750);
FORCEPROP 2 LAST CDS_LIB analog
J 0
(-450 3750);
DISPLAY INVISIBLE (-450 3750);
FORCEADD OFFPAGE_OUT..1
R 2
(-9650 6650);
FORCEPROP 2 LAST $XR0 10C5< 
J 0
(-9833 6650);
DISPLAY 0.638298 (-9833 6650);
PAINT MONO (-9833 6650);
FORCEPROP 2 LAST CDS_LIB cls
J 0
(-9650 6650);
DISPLAY INVISIBLE (-9650 6650);
FORCEPROP 1 LAST CDS_LMAN_SYM_OUTLINE -50,50,50,-50
J 2
(-9650 6650);
DISPLAY 0.468085 (-9650 6650);
PAINT GREEN (-9650 6650);
DISPLAY INVISIBLE (-9650 6650);
FORCEPROP 1 LAST BODY_TYPE COMMENT
J 2
(-9660 6785);
DISPLAY 0.808511 (-9660 6785);
PAINT GREEN (-9660 6785);
DISPLAY INVISIBLE (-9660 6785);
FORCEPROP 1 LAST OFFPAGE TRUE
J 2
(-9660 6705);
DISPLAY 0.808511 (-9660 6705);
PAINT GREEN (-9660 6705);
DISPLAY INVISIBLE (-9660 6705);
FORCEPROP 2 LAST PATH I14
J 0
(-9800 6700);
DISPLAY 1.021277 (-9800 6700);
DISPLAY INVISIBLE (-9800 6700);
FORCEADD VCC..1
(-750 4100);
FORCEPROP 3 LASTPIN (-700 4050) SIG_NAME XP3R3V_FPGA\g
J 0
(-690 4060);
DISPLAY 0.659574 (-690 4060);
PAINT MONO (-690 4060);
DISPLAY INVISIBLE (-690 4060);
FORCEPROP 0 LAST VOLTAGE 3.3V
J 0
(-1000 4250);
DISPLAY 1.021277 (-1000 4250);
DISPLAY BOTH (-1000 4250);
FORCEPROP 1 LAST HDL_POWER XP3R3V_FPGA
J 1
(-695 4155);
DISPLAY 1.021277 (-695 4155);
PAINT GREEN (-695 4155);
FORCEPROP 1 LAST CDS_LMAN_SYM_OUTLINE -250,250,250,-250
J 0
(-750 4100);
DISPLAY 0.468085 (-750 4100);
PAINT GREEN (-750 4100);
DISPLAY INVISIBLE (-750 4100);
FORCEPROP 2 LAST CDS_LIB cls
J 0
(-750 4100);
DISPLAY INVISIBLE (-750 4100);
FORCEPROP 1 LAST PATH I140
J 0
(-715 4190);
DISPLAY 0.808511 (-715 4190);
PAINT GREEN (-715 4190);
DISPLAY INVISIBLE (-715 4190);
FORCEPROP 1 LAST BODY_TYPE PLUMBING
J 0
(-795 4057);
DISPLAY 0.340426 (-795 4057);
PAINT GREEN (-795 4057);
DISPLAY INVISIBLE (-795 4057);
FORCEADD OFFPAGE_OUT..1
(1900 3650);
FORCEPROP 2 LAST $XR0 12F5< 
J 0
(1955 3650);
DISPLAY 0.638298 (1955 3650);
PAINT MONO (1955 3650);
FORCEPROP 1 LAST CDS_LMAN_SYM_OUTLINE -50,50,50,-50
J 0
(1900 3650);
DISPLAY 0.468085 (1900 3650);
PAINT GREEN (1900 3650);
DISPLAY INVISIBLE (1900 3650);
FORCEPROP 2 LAST CDS_LIB cls
J 0
(1900 3650);
DISPLAY INVISIBLE (1900 3650);
FORCEPROP 1 LAST BODY_TYPE COMMENT
J 0
(1910 3785);
DISPLAY 0.808511 (1910 3785);
PAINT GREEN (1910 3785);
DISPLAY INVISIBLE (1910 3785);
FORCEPROP 1 LAST OFFPAGE TRUE
J 0
(1910 3705);
DISPLAY 0.808511 (1910 3705);
PAINT GREEN (1910 3705);
DISPLAY INVISIBLE (1910 3705);
FORCEPROP 2 LAST PATH I141
J 0
(2000 3700);
DISPLAY 1.021277 (2000 3700);
DISPLAY INVISIBLE (2000 3700);
FORCEADD RESISTOR..2
(-1350 3650);
FORCEPROP 1 LAST $LOCATION R63
J 0
(-1300 3500);
DISPLAY 1.212766 (-1300 3500);
PAINT GREEN (-1300 3500);
FORCEPROP 0 LAST CDS_LOCATION R63
J 0
(-1300 3850);
DISPLAY 1.021277 (-1300 3850);
DISPLAY INVISIBLE (-1300 3850);
FORCEPROP 0 LAST $SEC 1
J 0
(-1300 3850);
DISPLAY 0.680851 (-1300 3850);
PAINT MONO (-1300 3850);
DISPLAY INVISIBLE (-1300 3850);
FORCEPROP 0 LAST CDS_SEC 1
J 0
(-1300 3850);
DISPLAY 1.021277 (-1300 3850);
DISPLAY INVISIBLE (-1300 3850);
FORCEPROP 0 LASTPIN (-1350 3750) $PN 1
R 1
J 0
(-1360 3760);
DISPLAY 0.680851 (-1360 3760);
PAINT MONO (-1360 3760);
FORCEPROP 0 LASTPIN (-1350 3500) $PN 2
R 1
J 2
(-1360 3490);
DISPLAY 0.680851 (-1360 3490);
PAINT MONO (-1360 3490);
FORCEPROP 0 LAST PACKAGE 0402
J 0
(-1300 3800);
DISPLAY 1.021277 (-1300 3800);
FORCEPROP 1 LAST VALUE 4.7KOHM
J 0
(-1300 3700);
DISPLAY 0.978723 (-1300 3700);
PAINT GREEN (-1300 3700);
FORCEPROP 1 LAST TOLERANCE 1%
J 0
(-1547 3905);
DISPLAY 1.212766 (-1547 3905);
PAINT GREEN (-1547 3905);
DISPLAY INVISIBLE (-1547 3905);
FORCEPROP 1 LAST CLS_PN G155-14701-01
J 0
(-1486 3850);
DISPLAY 1.212766 (-1486 3850);
PAINT GREEN (-1486 3850);
DISPLAY INVISIBLE (-1486 3850);
FORCEPROP 1 LAST PATH I144
J 0
(-1547 3755);
DISPLAY 1.212766 (-1547 3755);
PAINT GREEN (-1547 3755);
DISPLAY INVISIBLE (-1547 3755);
FORCEPROP 1 LAST CDS_LMAN_SYM_OUTLINE -50,50,50,-100
J 0
(-1350 3650);
DISPLAY 0.468085 (-1350 3650);
PAINT GREEN (-1350 3650);
DISPLAY INVISIBLE (-1350 3650);
FORCEPROP 2 LAST CDS_LIB passive
J 0
(-1350 3650);
DISPLAY INVISIBLE (-1350 3650);
FORCEADD RESISTOR..2
(850 4000);
FORCEPROP 1 LAST $LOCATION R167
J 0
(900 3850);
DISPLAY 0.978723 (900 3850);
PAINT GREEN (900 3850);
FORCEPROP 0 LAST CDS_LOCATION R167
J 0
(900 4100);
PAINT MONO (900 4100);
DISPLAY INVISIBLE (900 4100);
FORCEPROP 0 LAST $SEC 1
J 0
(900 4100);
PAINT MONO (900 4100);
DISPLAY INVISIBLE (900 4100);
FORCEPROP 0 LAST CDS_SEC 1
J 0
(900 4100);
PAINT MONO (900 4100);
DISPLAY INVISIBLE (900 4100);
FORCEPROP 0 LASTPIN (850 4100) $PN 1
R 1
J 0
(840 4110);
DISPLAY 0.808511 (840 4110);
PAINT MONO (840 4110);
FORCEPROP 0 LASTPIN (850 3850) $PN 2
R 1
J 2
(840 3840);
DISPLAY 0.808511 (840 3840);
PAINT MONO (840 3840);
FORCEPROP 1 LAST VALUE 10KOHM
J 0
(900 4050);
DISPLAY 0.787234 (900 4050);
PAINT GREEN (900 4050);
FORCEPROP 0 LAST PACKAGE 0402
J 0
(900 3950);
DISPLAY 0.808511 (900 3950);
FORCEPROP 1 LAST CLS_PN G155-11002-01
J 0
(714 4200);
DISPLAY 1.212766 (714 4200);
PAINT GREEN (714 4200);
DISPLAY INVISIBLE (714 4200);
FORCEPROP 1 LAST TOLERANCE 1%
J 0
(653 4255);
DISPLAY 1.212766 (653 4255);
PAINT GREEN (653 4255);
DISPLAY INVISIBLE (653 4255);
FORCEPROP 1 LAST CDS_LMAN_SYM_OUTLINE -50,50,50,-100
J 0
(850 4000);
DISPLAY 0.468085 (850 4000);
PAINT GREEN (850 4000);
DISPLAY INVISIBLE (850 4000);
FORCEPROP 1 LAST PATH I148
J 0
(653 4105);
DISPLAY 1.212766 (653 4105);
PAINT GREEN (653 4105);
DISPLAY INVISIBLE (653 4105);
FORCEPROP 2 LAST CDS_LIB passive
J 0
(850 4000);
DISPLAY INVISIBLE (850 4000);
FORCEADD VCC..1
(800 4350);
FORCEPROP 3 LASTPIN (850 4300) SIG_NAME XP3R3V_FPGA\g
J 0
(860 4310);
DISPLAY 0.659574 (860 4310);
PAINT MONO (860 4310);
DISPLAY INVISIBLE (860 4310);
FORCEPROP 0 LAST VOLTAGE 3.3V
J 0
(550 4500);
DISPLAY 1.021277 (550 4500);
DISPLAY BOTH (550 4500);
FORCEPROP 1 LAST HDL_POWER XP3R3V_FPGA
J 1
(855 4405);
DISPLAY 1.021277 (855 4405);
PAINT GREEN (855 4405);
FORCEPROP 1 LAST BODY_TYPE PLUMBING
J 0
(755 4307);
DISPLAY 0.340426 (755 4307);
PAINT GREEN (755 4307);
DISPLAY INVISIBLE (755 4307);
FORCEPROP 1 LAST CDS_LMAN_SYM_OUTLINE -250,250,250,-250
J 0
(800 4350);
DISPLAY 0.468085 (800 4350);
PAINT GREEN (800 4350);
DISPLAY INVISIBLE (800 4350);
FORCEPROP 1 LAST PATH I149
J 0
(835 4440);
DISPLAY 0.808511 (835 4440);
PAINT GREEN (835 4440);
DISPLAY INVISIBLE (835 4440);
FORCEPROP 2 LAST CDS_LIB cls
J 0
(800 4350);
DISPLAY INVISIBLE (800 4350);
FORCEADD RESISTOR..1
(-8250 5050);
FORCEPROP 1 LAST $LOCATION R23
J 2
(-8500 5050);
DISPLAY 1.212766 (-8500 5050);
PAINT GREEN (-8500 5050);
FORCEPROP 0 LAST CDS_LOCATION R23
J 0
(-8000 5150);
DISPLAY 1.021277 (-8000 5150);
DISPLAY INVISIBLE (-8000 5150);
FORCEPROP 0 LAST $SEC 1
J 0
(-8000 5150);
DISPLAY 0.680851 (-8000 5150);
PAINT MONO (-8000 5150);
DISPLAY INVISIBLE (-8000 5150);
FORCEPROP 0 LAST CDS_SEC 1
J 0
(-8000 5150);
DISPLAY 1.021277 (-8000 5150);
DISPLAY INVISIBLE (-8000 5150);
FORCEPROP 0 LASTPIN (-8350 5050) $PN 1
J 2
(-8360 5060);
DISPLAY 0.680851 (-8360 5060);
PAINT MONO (-8360 5060);
FORCEPROP 0 LASTPIN (-8100 5050) $PN 2
J 0
(-8090 5060);
DISPLAY 0.680851 (-8090 5060);
PAINT MONO (-8090 5060);
FORCEPROP 0 LAST PACKAGE 0402
J 0
(-8300 5100);
DISPLAY 0.808511 (-8300 5100);
FORCEPROP 1 LAST VALUE 0OHM
J 0
(-8000 5050);
DISPLAY 1.212766 (-8000 5050);
PAINT GREEN (-8000 5050);
FORCEPROP 2 LAST CDS_LIB passive
J 0
(-8250 5050);
DISPLAY INVISIBLE (-8250 5050);
FORCEPROP 1 LAST CDS_LMAN_SYM_OUTLINE -50,50,100,-50
J 0
(-8250 5050);
DISPLAY 0.468085 (-8250 5050);
PAINT GREEN (-8250 5050);
DISPLAY INVISIBLE (-8250 5050);
FORCEPROP 1 LAST CLS_PN G155-100R0-J0
J 0
(-8386 5250);
DISPLAY 1.212766 (-8386 5250);
PAINT GREEN (-8386 5250);
DISPLAY INVISIBLE (-8386 5250);
FORCEPROP 1 LAST TOLERANCE -
J 0
(-8447 5305);
DISPLAY 1.212766 (-8447 5305);
PAINT GREEN (-8447 5305);
DISPLAY INVISIBLE (-8447 5305);
FORCEPROP 1 LAST PATH I15
J 0
(-8447 5155);
DISPLAY 1.212766 (-8447 5155);
PAINT GREEN (-8447 5155);
DISPLAY INVISIBLE (-8447 5155);
FORCEADD GND_SG..1
(400 3050);
FORCEPROP 3 LASTPIN (450 3100) SIG_NAME SG\g
J 0
(460 3110);
DISPLAY 0.659574 (460 3110);
PAINT MONO (460 3110);
DISPLAY INVISIBLE (460 3110);
FORCEPROP 1 LAST HDL_POWER SG
J 1
(455 2955);
DISPLAY 0.808511 (455 2955);
PAINT GREEN (455 2955);
FORCEPROP 2 LAST CDS_LIB cls
J 0
(400 3050);
DISPLAY INVISIBLE (400 3050);
FORCEPROP 1 LAST PATH I150
J 0
(435 3050);
DISPLAY 0.808511 (435 3050);
PAINT GREEN (435 3050);
DISPLAY INVISIBLE (435 3050);
FORCEPROP 1 LAST CDS_LMAN_SYM_OUTLINE 0,0,100,-50
J 0
(400 3050);
DISPLAY 0.468085 (400 3050);
PAINT GREEN (400 3050);
DISPLAY INVISIBLE (400 3050);
FORCEPROP 1 LAST BODY_TYPE PLUMBING
J 0
(415 3035);
DISPLAY 0.808511 (415 3035);
PAINT GREEN (415 3035);
DISPLAY INVISIBLE (415 3035);
FORCEADD RESISTOR..2
(450 4000);
FORCEPROP 1 LAST $LOCATION R164
J 0
(500 3850);
DISPLAY 0.978723 (500 3850);
PAINT GREEN (500 3850);
FORCEPROP 0 LAST CDS_LOCATION R164
J 0
(450 4150);
PAINT MONO (450 4150);
DISPLAY INVISIBLE (450 4150);
FORCEPROP 0 LAST $SEC 1
J 0
(450 4150);
PAINT MONO (450 4150);
DISPLAY INVISIBLE (450 4150);
FORCEPROP 0 LAST CDS_SEC 1
J 0
(450 4150);
PAINT MONO (450 4150);
DISPLAY INVISIBLE (450 4150);
FORCEPROP 0 LASTPIN (450 4100) $PN 1
R 1
J 0
(440 4110);
DISPLAY 0.808511 (440 4110);
PAINT MONO (440 4110);
FORCEPROP 0 LASTPIN (450 3850) $PN 2
R 1
J 2
(440 3840);
DISPLAY 0.808511 (440 3840);
PAINT MONO (440 3840);
FORCEPROP 1 LAST VALUE 100KOHM
J 0
(500 4050);
DISPLAY 0.787234 (500 4050);
PAINT GREEN (500 4050);
FORCEPROP 0 LAST NO_ASSY TRUE
J 0
(450 4100);
DISPLAY 0.638298 (450 4100);
DISPLAY BOTH (450 4100);
FORCEPROP 0 LAST PACKAGE 0402
J 0
(500 3950);
DISPLAY 0.808511 (500 3950);
FORCEPROP 2 LAST CDS_LIB passive
J 0
(450 4000);
DISPLAY INVISIBLE (450 4000);
FORCEPROP 1 LAST PATH I151
J 0
(253 4105);
DISPLAY 1.212766 (253 4105);
PAINT GREEN (253 4105);
DISPLAY INVISIBLE (253 4105);
FORCEPROP 1 LAST CDS_LMAN_SYM_OUTLINE -50,50,50,-100
J 0
(450 4000);
DISPLAY 0.468085 (450 4000);
PAINT GREEN (450 4000);
DISPLAY INVISIBLE (450 4000);
FORCEPROP 1 LAST TOLERANCE 1%
J 0
(253 4255);
DISPLAY 1.212766 (253 4255);
PAINT GREEN (253 4255);
DISPLAY INVISIBLE (253 4255);
FORCEPROP 1 LAST CLS_PN G155-11003-01
J 0
(314 4200);
DISPLAY 1.212766 (314 4200);
PAINT GREEN (314 4200);
DISPLAY INVISIBLE (314 4200);
FORCEPROP 2 LASTPIN (450 3850) SIG_NAME UN$3$RESISTOR$I151$2
J 0
(460 3860);
DISPLAY 0.659574 (460 3860);
PAINT MONO (460 3860);
DISPLAY INVISIBLE (460 3860);
FORCEADD CAPACITOR..2
R 2
(650 3350);
FORCEPROP 1 LAST $LOCATION C250
J 2
(850 3200);
DISPLAY 1.212766 (850 3200);
PAINT GREEN (850 3200);
FORCEPROP 0 LAST CDS_LOCATION C250
J 0
(950 3450);
PAINT MONO (950 3450);
DISPLAY INVISIBLE (950 3450);
FORCEPROP 0 LAST $SEC 1
J 0
(950 3450);
PAINT MONO (950 3450);
DISPLAY INVISIBLE (950 3450);
FORCEPROP 0 LAST CDS_SEC 1
J 0
(950 3450);
PAINT MONO (950 3450);
DISPLAY INVISIBLE (950 3450);
FORCEPROP 0 LASTPIN (650 3450) $PN 1
R 1
J 0
(640 3460);
DISPLAY 0.808511 (640 3460);
PAINT MONO (640 3460);
FORCEPROP 0 LASTPIN (650 3200) $PN 2
R 1
J 2
(640 3190);
DISPLAY 0.808511 (640 3190);
PAINT MONO (640 3190);
FORCEPROP 0 LAST PACKAGE 0402
J 0
(950 3400);
DISPLAY 1.021277 (950 3400);
FORCEPROP 0 LAST VOLTAGE 25V
J 0
(750 3400);
DISPLAY 1.021277 (750 3400);
FORCEPROP 1 LAST VALUE 0.1UF
J 2
(1050 3300);
DISPLAY 1.212766 (1050 3300);
PAINT GREEN (1050 3300);
FORCEPROP 2 LAST CDS_LIB passive
J 0
(650 3350);
DISPLAY INVISIBLE (650 3350);
FORCEPROP 1 LAST PATH I152
J 2
(750 3400);
DISPLAY 1.212766 (750 3400);
PAINT GREEN (750 3400);
DISPLAY INVISIBLE (750 3400);
FORCEPROP 1 LAST CDS_LMAN_SYM_OUTLINE -50,0,50,-50
J 2
(650 3350);
DISPLAY 0.468085 (650 3350);
PAINT GREEN (650 3350);
DISPLAY INVISIBLE (650 3350);
FORCEPROP 1 LAST TOLERANCE 10%
J 2
(800 3450);
DISPLAY 1.212766 (800 3450);
PAINT GREEN (800 3450);
DISPLAY INVISIBLE (800 3450);
FORCEPROP 1 LAST CLS_PN G105-0B104-EK
J 2
(750 3400);
DISPLAY 1.212766 (750 3400);
PAINT GREEN (750 3400);
DISPLAY INVISIBLE (750 3400);
FORCEADD RESISTOR..1
(900 7000);
FORCEPROP 1 LAST $LOCATION R57
J 2
(700 7000);
DISPLAY 1.212766 (700 7000);
PAINT GREEN (700 7000);
FORCEPROP 0 LAST CDS_LOCATION R57
J 0
(1100 7100);
DISPLAY 1.021277 (1100 7100);
DISPLAY INVISIBLE (1100 7100);
FORCEPROP 0 LAST $SEC 1
J 0
(1100 7100);
DISPLAY 0.680851 (1100 7100);
PAINT MONO (1100 7100);
DISPLAY INVISIBLE (1100 7100);
FORCEPROP 0 LAST CDS_SEC 1
J 0
(1100 7100);
DISPLAY 1.021277 (1100 7100);
DISPLAY INVISIBLE (1100 7100);
FORCEPROP 0 LASTPIN (800 7000) $PN 1
J 2
(790 7010);
DISPLAY 0.680851 (790 7010);
PAINT MONO (790 7010);
FORCEPROP 0 LASTPIN (1050 7000) $PN 2
J 0
(1060 7010);
DISPLAY 0.680851 (1060 7010);
PAINT MONO (1060 7010);
FORCEPROP 1 LAST VALUE 33OHM
J 0
(1150 7000);
DISPLAY 1.212766 (1150 7000);
PAINT GREEN (1150 7000);
FORCEPROP 0 LAST PACKAGE 0402
J 0
(850 6900);
DISPLAY 0.808511 (850 6900);
FORCEPROP 1 LAST PATH I153
J 0
(703 7105);
DISPLAY 1.212766 (703 7105);
PAINT GREEN (703 7105);
DISPLAY INVISIBLE (703 7105);
FORCEPROP 2 LAST CDS_LIB passive
J 0
(900 7000);
DISPLAY INVISIBLE (900 7000);
FORCEPROP 1 LAST CDS_LMAN_SYM_OUTLINE -50,50,100,-50
J 0
(900 7000);
DISPLAY 0.468085 (900 7000);
PAINT GREEN (900 7000);
DISPLAY INVISIBLE (900 7000);
FORCEPROP 1 LAST CLS_PN G155-133R0-01
J 0
(764 7200);
DISPLAY 1.212766 (764 7200);
PAINT GREEN (764 7200);
DISPLAY INVISIBLE (764 7200);
FORCEPROP 1 LAST TOLERANCE 1%
J 0
(703 7255);
DISPLAY 1.212766 (703 7255);
PAINT GREEN (703 7255);
DISPLAY INVISIBLE (703 7255);
FORCEADD OFFPAGE_OUT..1
(2300 7000);
FORCEPROP 2 LAST $XR0 9J10< 
J 0
(2355 7000);
DISPLAY 0.638298 (2355 7000);
PAINT MONO (2355 7000);
FORCEPROP 2 LAST CDS_LIB cls
J 0
(2300 7000);
DISPLAY INVISIBLE (2300 7000);
FORCEPROP 2 LAST PATH I154
J 0
(2350 7100);
DISPLAY 1.021277 (2350 7100);
DISPLAY INVISIBLE (2350 7100);
FORCEPROP 1 LAST CDS_LMAN_SYM_OUTLINE -50,50,50,-50
J 0
(2300 7000);
DISPLAY 0.468085 (2300 7000);
PAINT GREEN (2300 7000);
DISPLAY INVISIBLE (2300 7000);
FORCEPROP 1 LAST BODY_TYPE COMMENT
J 0
(2310 7135);
DISPLAY 0.808511 (2310 7135);
PAINT GREEN (2310 7135);
DISPLAY INVISIBLE (2310 7135);
FORCEPROP 1 LAST OFFPAGE TRUE
J 0
(2310 7055);
DISPLAY 0.808511 (2310 7055);
PAINT GREEN (2310 7055);
DISPLAY INVISIBLE (2310 7055);
FORCEADD OFFPAGE_IN..1
(-2300 3250);
FORCEPROP 2 LAST $XR0 9E15> 
J 0
(-2483 3250);
DISPLAY 0.638298 (-2483 3250);
PAINT MONO (-2483 3250);
FORCEPROP 2 LAST CDS_LIB cls
J 0
(-2300 3250);
DISPLAY INVISIBLE (-2300 3250);
FORCEPROP 2 LAST PATH I155
J 0
(-2250 3350);
DISPLAY 1.021277 (-2250 3350);
DISPLAY INVISIBLE (-2250 3350);
FORCEPROP 1 LAST CDS_LMAN_SYM_OUTLINE -50,50,50,-50
J 0
(-2300 3250);
DISPLAY 0.468085 (-2300 3250);
PAINT GREEN (-2300 3250);
DISPLAY INVISIBLE (-2300 3250);
FORCEPROP 1 LAST OFFPAGE TRUE
J 0
(-2290 3305);
DISPLAY 0.808511 (-2290 3305);
PAINT GREEN (-2290 3305);
DISPLAY INVISIBLE (-2290 3305);
FORCEPROP 1 LAST BODY_TYPE COMMENT
J 0
(-2290 3385);
DISPLAY 0.808511 (-2290 3385);
PAINT GREEN (-2290 3385);
DISPLAY INVISIBLE (-2290 3385);
FORCEADD RESISTOR..1
(-8400 6450);
FORCEPROP 1 LAST $LOCATION R22
J 2
(-8650 6450);
DISPLAY 1.212766 (-8650 6450);
PAINT GREEN (-8650 6450);
FORCEPROP 0 LAST CDS_LOCATION R22
J 0
(-8150 6550);
DISPLAY 1.021277 (-8150 6550);
DISPLAY INVISIBLE (-8150 6550);
FORCEPROP 0 LAST $SEC 1
J 0
(-8150 6550);
DISPLAY 0.680851 (-8150 6550);
PAINT MONO (-8150 6550);
DISPLAY INVISIBLE (-8150 6550);
FORCEPROP 0 LAST CDS_SEC 1
J 0
(-8150 6550);
DISPLAY 1.021277 (-8150 6550);
DISPLAY INVISIBLE (-8150 6550);
FORCEPROP 0 LASTPIN (-8500 6450) $PN 1
J 2
(-8510 6460);
DISPLAY 0.680851 (-8510 6460);
PAINT MONO (-8510 6460);
FORCEPROP 0 LASTPIN (-8250 6450) $PN 2
J 0
(-8240 6460);
DISPLAY 0.680851 (-8240 6460);
PAINT MONO (-8240 6460);
FORCEPROP 1 LAST VALUE 0OHM
J 0
(-8150 6450);
DISPLAY 1.212766 (-8150 6450);
PAINT GREEN (-8150 6450);
FORCEPROP 0 LAST PACKAGE 0402
J 0
(-8450 6500);
DISPLAY 0.808511 (-8450 6500);
FORCEPROP 0 LAST NO_ASSY TRUE
J 0
(-8550 6400);
DISPLAY 0.638298 (-8550 6400);
DISPLAY BOTH (-8550 6400);
FORCEPROP 2 LAST CDS_LIB passive
J 0
(-8400 6450);
DISPLAY INVISIBLE (-8400 6450);
FORCEPROP 1 LAST CDS_LMAN_SYM_OUTLINE -50,50,100,-50
J 0
(-8400 6450);
DISPLAY 0.468085 (-8400 6450);
PAINT GREEN (-8400 6450);
DISPLAY INVISIBLE (-8400 6450);
FORCEPROP 1 LAST CLS_PN G155-100R0-J0
J 0
(-8536 6650);
DISPLAY 1.212766 (-8536 6650);
PAINT GREEN (-8536 6650);
DISPLAY INVISIBLE (-8536 6650);
FORCEPROP 1 LAST TOLERANCE -
J 0
(-8597 6705);
DISPLAY 1.212766 (-8597 6705);
PAINT GREEN (-8597 6705);
DISPLAY INVISIBLE (-8597 6705);
FORCEPROP 1 LAST PATH I16
J 0
(-8597 6555);
DISPLAY 1.212766 (-8597 6555);
PAINT GREEN (-8597 6555);
DISPLAY INVISIBLE (-8597 6555);
FORCEADD GND_SG..1
(-1300 6350);
FORCEPROP 3 LASTPIN (-1250 6400) SIG_NAME SG\g
J 0
(-1240 6410);
DISPLAY 0.659574 (-1240 6410);
PAINT MONO (-1240 6410);
DISPLAY INVISIBLE (-1240 6410);
FORCEPROP 1 LAST HDL_POWER SG
J 1
(-1245 6255);
DISPLAY 0.808511 (-1245 6255);
PAINT GREEN (-1245 6255);
FORCEPROP 1 LAST CDS_LMAN_SYM_OUTLINE 0,0,100,-50
J 0
(-1300 6350);
DISPLAY 0.468085 (-1300 6350);
PAINT GREEN (-1300 6350);
DISPLAY INVISIBLE (-1300 6350);
FORCEPROP 2 LAST CDS_LIB cls
J 0
(-1300 6350);
DISPLAY INVISIBLE (-1300 6350);
FORCEPROP 1 LAST PATH I18
J 0
(-1265 6350);
DISPLAY 0.808511 (-1265 6350);
PAINT GREEN (-1265 6350);
DISPLAY INVISIBLE (-1265 6350);
FORCEPROP 1 LAST BODY_TYPE PLUMBING
J 0
(-1285 6335);
DISPLAY 0.808511 (-1285 6335);
PAINT GREEN (-1285 6335);
DISPLAY INVISIBLE (-1285 6335);
FORCEADD VCC..1
(-1350 7900);
FORCEPROP 3 LASTPIN (-1300 7850) SIG_NAME XP3R3V\g
J 0
(-1290 7860);
DISPLAY 0.659574 (-1290 7860);
PAINT MONO (-1290 7860);
DISPLAY INVISIBLE (-1290 7860);
FORCEPROP 0 LAST VOLTAGE 3.3
J 0
(-1500 8000);
DISPLAY 0.808511 (-1500 8000);
DISPLAY BOTH (-1500 8000);
FORCEPROP 1 LAST HDL_POWER XP3R3V
J 1
(-1300 7950);
DISPLAY 0.808511 (-1300 7950);
PAINT GREEN (-1300 7950);
FORCEPROP 2 LAST CDS_LIB cls
J 0
(-1350 7900);
DISPLAY INVISIBLE (-1350 7900);
FORCEPROP 1 LAST CDS_LMAN_SYM_OUTLINE -250,250,250,-250
J 0
(-1350 7900);
DISPLAY 0.468085 (-1350 7900);
PAINT GREEN (-1350 7900);
DISPLAY INVISIBLE (-1350 7900);
FORCEPROP 1 LAST BODY_TYPE PLUMBING
J 0
(-1395 7857);
DISPLAY 0.340426 (-1395 7857);
PAINT GREEN (-1395 7857);
DISPLAY INVISIBLE (-1395 7857);
FORCEPROP 1 LAST PATH I19
J 0
(-1315 7990);
DISPLAY 0.808511 (-1315 7990);
PAINT GREEN (-1315 7990);
DISPLAY INVISIBLE (-1315 7990);
FORCEADD GND_SG..1
(-7350 4750);
FORCEPROP 3 LASTPIN (-7300 4800) SIG_NAME SG\g
J 0
(-7290 4810);
DISPLAY 0.659574 (-7290 4810);
PAINT MONO (-7290 4810);
DISPLAY INVISIBLE (-7290 4810);
FORCEPROP 1 LAST HDL_POWER SG
J 1
(-7295 4655);
DISPLAY 0.808511 (-7295 4655);
PAINT GREEN (-7295 4655);
FORCEPROP 1 LAST PATH I20
J 0
(-7315 4750);
DISPLAY 0.808511 (-7315 4750);
PAINT GREEN (-7315 4750);
DISPLAY INVISIBLE (-7315 4750);
FORCEPROP 1 LAST BODY_TYPE PLUMBING
J 0
(-7335 4735);
DISPLAY 0.808511 (-7335 4735);
PAINT GREEN (-7335 4735);
DISPLAY INVISIBLE (-7335 4735);
FORCEPROP 2 LAST CDS_LIB cls
J 0
(-7350 4750);
DISPLAY INVISIBLE (-7350 4750);
FORCEPROP 1 LAST CDS_LMAN_SYM_OUTLINE 0,0,100,-50
J 0
(-7350 4750);
DISPLAY 0.468085 (-7350 4750);
PAINT GREEN (-7350 4750);
DISPLAY INVISIBLE (-7350 4750);
FORCEADD VCC..1
(-8700 8850);
FORCEPROP 3 LASTPIN (-8650 8800) SIG_NAME XP3R3V_AUX_PCIE\g
J 0
(-8640 8810);
DISPLAY 0.659574 (-8640 8810);
PAINT MONO (-8640 8810);
DISPLAY INVISIBLE (-8640 8810);
FORCEPROP 0 LAST VOLTAGE 3.3
J 1
(-8650 8950);
DISPLAY 1.021277 (-8650 8950);
DISPLAY BOTH (-8650 8950);
FORCEPROP 1 LAST HDL_POWER XP3R3V_AUX_PCIE
J 1
(-8650 8900);
DISPLAY 0.808511 (-8650 8900);
PAINT GREEN (-8650 8900);
FORCEPROP 2 LAST CDS_LIB cls
J 0
(-8700 8850);
DISPLAY INVISIBLE (-8700 8850);
FORCEPROP 1 LAST CDS_LMAN_SYM_OUTLINE -250,250,250,-250
J 0
(-8700 8850);
DISPLAY 0.468085 (-8700 8850);
PAINT GREEN (-8700 8850);
DISPLAY INVISIBLE (-8700 8850);
FORCEPROP 1 LAST BODY_TYPE PLUMBING
J 0
(-8745 8807);
DISPLAY 0.340426 (-8745 8807);
PAINT GREEN (-8745 8807);
DISPLAY INVISIBLE (-8745 8807);
FORCEPROP 1 LAST PATH I23
J 0
(-8665 8940);
DISPLAY 0.808511 (-8665 8940);
PAINT GREEN (-8665 8940);
DISPLAY INVISIBLE (-8665 8940);
FORCEADD VCC..1
(-8000 8850);
FORCEPROP 3 LASTPIN (-7950 8800) SIG_NAME XP3R3V_PCIE\g
J 0
(-7940 8810);
DISPLAY 0.659574 (-7940 8810);
PAINT MONO (-7940 8810);
DISPLAY INVISIBLE (-7940 8810);
FORCEPROP 0 LAST VOLTAGE 3.3
J 1
(-7950 8950);
DISPLAY 1.021277 (-7950 8950);
DISPLAY BOTH (-7950 8950);
FORCEPROP 1 LAST HDL_POWER XP3R3V_PCIE
J 1
(-7950 8900);
DISPLAY 0.808511 (-7950 8900);
PAINT GREEN (-7950 8900);
FORCEPROP 2 LAST CDS_LIB cls
J 0
(-8000 8850);
DISPLAY INVISIBLE (-8000 8850);
FORCEPROP 1 LAST CDS_LMAN_SYM_OUTLINE -250,250,250,-250
J 0
(-8000 8850);
DISPLAY 0.468085 (-8000 8850);
PAINT GREEN (-8000 8850);
DISPLAY INVISIBLE (-8000 8850);
FORCEPROP 1 LAST BODY_TYPE PLUMBING
J 0
(-8045 8807);
DISPLAY 0.340426 (-8045 8807);
PAINT GREEN (-8045 8807);
DISPLAY INVISIBLE (-8045 8807);
FORCEPROP 1 LAST PATH I24
J 0
(-7965 8940);
DISPLAY 0.808511 (-7965 8940);
PAINT GREEN (-7965 8940);
DISPLAY INVISIBLE (-7965 8940);
FORCEADD VCC..1
(-7400 8850);
FORCEPROP 3 LASTPIN (-7350 8800) SIG_NAME XP12R0V_PCIE\g
J 0
(-7340 8810);
DISPLAY 0.659574 (-7340 8810);
PAINT MONO (-7340 8810);
DISPLAY INVISIBLE (-7340 8810);
FORCEPROP 1 LAST HDL_POWER XP12R0V_PCIE
J 1
(-7350 8900);
DISPLAY 0.808511 (-7350 8900);
PAINT GREEN (-7350 8900);
FORCEPROP 0 LAST VOLTAGE 12
J 1
(-7350 8950);
DISPLAY 1.021277 (-7350 8950);
DISPLAY BOTH (-7350 8950);
FORCEPROP 1 LAST CDS_LMAN_SYM_OUTLINE -250,250,250,-250
J 0
(-7400 8850);
DISPLAY 0.468085 (-7400 8850);
PAINT GREEN (-7400 8850);
DISPLAY INVISIBLE (-7400 8850);
FORCEPROP 2 LAST CDS_LIB cls
J 0
(-7400 8850);
DISPLAY INVISIBLE (-7400 8850);
FORCEPROP 1 LAST BODY_TYPE PLUMBING
J 0
(-7445 8807);
DISPLAY 0.340426 (-7445 8807);
PAINT GREEN (-7445 8807);
DISPLAY INVISIBLE (-7445 8807);
FORCEPROP 1 LAST PATH I25
J 0
(-7365 8940);
DISPLAY 0.808511 (-7365 8940);
PAINT GREEN (-7365 8940);
DISPLAY INVISIBLE (-7365 8940);
FORCEADD GND_SG..1
(-5750 4750);
FORCEPROP 3 LASTPIN (-5700 4800) SIG_NAME SG\g
J 0
(-5690 4810);
DISPLAY 0.659574 (-5690 4810);
PAINT MONO (-5690 4810);
DISPLAY INVISIBLE (-5690 4810);
FORCEPROP 1 LAST HDL_POWER SG
J 1
(-5695 4655);
DISPLAY 0.808511 (-5695 4655);
PAINT GREEN (-5695 4655);
FORCEPROP 1 LAST PATH I26
J 0
(-5715 4750);
DISPLAY 0.808511 (-5715 4750);
PAINT GREEN (-5715 4750);
DISPLAY INVISIBLE (-5715 4750);
FORCEPROP 1 LAST BODY_TYPE PLUMBING
J 0
(-5735 4735);
DISPLAY 0.808511 (-5735 4735);
PAINT GREEN (-5735 4735);
DISPLAY INVISIBLE (-5735 4735);
FORCEPROP 2 LAST CDS_LIB cls
J 0
(-5750 4750);
DISPLAY INVISIBLE (-5750 4750);
FORCEPROP 1 LAST CDS_LMAN_SYM_OUTLINE 0,0,100,-50
J 0
(-5750 4750);
DISPLAY 0.468085 (-5750 4750);
PAINT GREEN (-5750 4750);
DISPLAY INVISIBLE (-5750 4750);
FORCEADD CAPACITOR..1
(-4000 6550);
FORCEPROP 1 LAST $LOCATION C24
J 2
(-4150 6550);
DISPLAY 1.212766 (-4150 6550);
PAINT GREEN (-4150 6550);
FORCEPROP 0 LAST CDS_LOCATION C24
J 0
(-3750 6650);
DISPLAY 1.021277 (-3750 6650);
DISPLAY INVISIBLE (-3750 6650);
FORCEPROP 0 LAST $SEC 1
J 0
(-3750 6650);
DISPLAY 0.680851 (-3750 6650);
PAINT MONO (-3750 6650);
DISPLAY INVISIBLE (-3750 6650);
FORCEPROP 0 LAST CDS_SEC 1
J 0
(-3750 6650);
DISPLAY 1.021277 (-3750 6650);
DISPLAY INVISIBLE (-3750 6650);
FORCEPROP 0 LASTPIN (-4100 6550) $PN 1
J 2
(-4110 6560);
DISPLAY 0.680851 (-4110 6560);
PAINT MONO (-4110 6560);
FORCEPROP 0 LASTPIN (-3850 6550) $PN 2
J 0
(-3840 6560);
DISPLAY 0.680851 (-3840 6560);
PAINT MONO (-3840 6560);
FORCEPROP 0 LAST PACKAGE 0402
J 0
(-3450 6550);
DISPLAY 1.021277 (-3450 6550);
FORCEPROP 1 LAST VALUE 0.1UF
J 0
(-3750 6550);
DISPLAY 1.212766 (-3750 6550);
PAINT GREEN (-3750 6550);
FORCEPROP 1 LAST TOLERANCE 10%
J 2
(-4100 6650);
DISPLAY 1.212766 (-4100 6650);
PAINT GREEN (-4100 6650);
DISPLAY INVISIBLE (-4100 6650);
FORCEPROP 2 LAST SIGNAL_MODEL DEFAULT_CAPACITOR_100000pF_1_2
J 0
(-4050 6750);
DISPLAY 1.021277 (-4050 6750);
DISPLAY INVISIBLE (-4050 6750);
FORCEPROP 1 LAST CLS_PN G105-0B104-CK
J 2
(-4050 6650);
DISPLAY 1.212766 (-4050 6650);
PAINT GREEN (-4050 6650);
DISPLAY INVISIBLE (-4050 6650);
FORCEPROP 1 LAST CDS_LMAN_SYM_OUTLINE 0,50,50,-50
J 0
(-4000 6550);
DISPLAY 0.468085 (-4000 6550);
PAINT GREEN (-4000 6550);
DISPLAY INVISIBLE (-4000 6550);
FORCEPROP 2 LAST CDS_LIB passive
J 0
(-4000 6550);
DISPLAY INVISIBLE (-4000 6550);
FORCEPROP 1 LAST PATH I35
J 2
(-4050 6650);
DISPLAY 1.212766 (-4050 6650);
PAINT GREEN (-4050 6650);
DISPLAY INVISIBLE (-4050 6650);
FORCEADD CAPACITOR..1
(-4000 6850);
FORCEPROP 1 LAST $LOCATION C19
J 2
(-4150 6850);
DISPLAY 1.212766 (-4150 6850);
PAINT GREEN (-4150 6850);
FORCEPROP 0 LAST CDS_LOCATION C19
J 0
(-3750 6950);
DISPLAY 1.021277 (-3750 6950);
DISPLAY INVISIBLE (-3750 6950);
FORCEPROP 0 LAST $SEC 1
J 0
(-3750 6950);
DISPLAY 0.680851 (-3750 6950);
PAINT MONO (-3750 6950);
DISPLAY INVISIBLE (-3750 6950);
FORCEPROP 0 LAST CDS_SEC 1
J 0
(-3750 6950);
DISPLAY 1.021277 (-3750 6950);
DISPLAY INVISIBLE (-3750 6950);
FORCEPROP 0 LASTPIN (-4100 6850) $PN 1
J 2
(-4110 6860);
DISPLAY 0.680851 (-4110 6860);
PAINT MONO (-4110 6860);
FORCEPROP 0 LASTPIN (-3850 6850) $PN 2
J 0
(-3840 6860);
DISPLAY 0.680851 (-3840 6860);
PAINT MONO (-3840 6860);
FORCEPROP 1 LAST VALUE 0.1UF
J 0
(-3750 6850);
DISPLAY 1.212766 (-3750 6850);
PAINT GREEN (-3750 6850);
FORCEPROP 0 LAST PACKAGE 0402
J 0
(-3450 6850);
DISPLAY 1.021277 (-3450 6850);
FORCEPROP 1 LAST TOLERANCE 10%
J 2
(-4100 6950);
DISPLAY 1.212766 (-4100 6950);
PAINT GREEN (-4100 6950);
DISPLAY INVISIBLE (-4100 6950);
FORCEPROP 2 LAST SIGNAL_MODEL DEFAULT_CAPACITOR_100000pF_1_2
J 0
(-4050 7050);
DISPLAY 1.021277 (-4050 7050);
DISPLAY INVISIBLE (-4050 7050);
FORCEPROP 1 LAST CLS_PN G105-0B104-CK
J 2
(-4050 6950);
DISPLAY 1.212766 (-4050 6950);
PAINT GREEN (-4050 6950);
DISPLAY INVISIBLE (-4050 6950);
FORCEPROP 1 LAST CDS_LMAN_SYM_OUTLINE 0,50,50,-50
J 0
(-4000 6850);
DISPLAY 0.468085 (-4000 6850);
PAINT GREEN (-4000 6850);
DISPLAY INVISIBLE (-4000 6850);
FORCEPROP 2 LAST CDS_LIB passive
J 0
(-4000 6850);
DISPLAY INVISIBLE (-4000 6850);
FORCEPROP 1 LAST PATH I36
J 2
(-4050 6950);
DISPLAY 1.212766 (-4050 6950);
PAINT GREEN (-4050 6950);
DISPLAY INVISIBLE (-4050 6950);
FORCEADD CAPACITOR..1
(-4000 6750);
FORCEPROP 1 LAST $LOCATION C23
J 2
(-4150 6750);
DISPLAY 1.212766 (-4150 6750);
PAINT GREEN (-4150 6750);
FORCEPROP 0 LAST CDS_LOCATION C23
J 0
(-3750 6850);
DISPLAY 1.021277 (-3750 6850);
DISPLAY INVISIBLE (-3750 6850);
FORCEPROP 0 LAST $SEC 1
J 0
(-3750 6850);
DISPLAY 0.680851 (-3750 6850);
PAINT MONO (-3750 6850);
DISPLAY INVISIBLE (-3750 6850);
FORCEPROP 0 LAST CDS_SEC 1
J 0
(-3750 6850);
DISPLAY 1.021277 (-3750 6850);
DISPLAY INVISIBLE (-3750 6850);
FORCEPROP 0 LASTPIN (-4100 6750) $PN 1
J 2
(-4110 6760);
DISPLAY 0.680851 (-4110 6760);
PAINT MONO (-4110 6760);
FORCEPROP 0 LASTPIN (-3850 6750) $PN 2
J 0
(-3840 6760);
DISPLAY 0.680851 (-3840 6760);
PAINT MONO (-3840 6760);
FORCEPROP 0 LAST PACKAGE 0402
J 0
(-3450 6750);
DISPLAY 1.021277 (-3450 6750);
FORCEPROP 1 LAST VALUE 0.1UF
J 0
(-3750 6750);
DISPLAY 1.212766 (-3750 6750);
PAINT GREEN (-3750 6750);
FORCEPROP 2 LAST CDS_LIB passive
J 0
(-4000 6750);
DISPLAY INVISIBLE (-4000 6750);
FORCEPROP 1 LAST CDS_LMAN_SYM_OUTLINE 0,50,50,-50
J 0
(-4000 6750);
DISPLAY 0.468085 (-4000 6750);
PAINT GREEN (-4000 6750);
DISPLAY INVISIBLE (-4000 6750);
FORCEPROP 1 LAST CLS_PN G105-0B104-CK
J 2
(-4050 6850);
DISPLAY 1.212766 (-4050 6850);
PAINT GREEN (-4050 6850);
DISPLAY INVISIBLE (-4050 6850);
FORCEPROP 2 LAST SIGNAL_MODEL DEFAULT_CAPACITOR_100000pF_1_2
J 0
(-4050 6950);
DISPLAY 1.021277 (-4050 6950);
DISPLAY INVISIBLE (-4050 6950);
FORCEPROP 1 LAST TOLERANCE 10%
J 2
(-4100 6850);
DISPLAY 1.212766 (-4100 6850);
PAINT GREEN (-4100 6850);
DISPLAY INVISIBLE (-4100 6850);
FORCEPROP 1 LAST PATH I37
J 2
(-4050 6850);
DISPLAY 1.212766 (-4050 6850);
PAINT GREEN (-4050 6850);
DISPLAY INVISIBLE (-4050 6850);
FORCEADD OFFPAGE_IN..2
(-2000 5150);
FORCEPROP 2 LAST $XR0 10D12> 
J 0
(-1945 5150);
DISPLAY 0.638298 (-1945 5150);
PAINT MONO (-1945 5150);
FORCEPROP 2 LAST CDS_LIB cls
J 0
(-2000 5150);
DISPLAY INVISIBLE (-2000 5150);
FORCEPROP 1 LAST CDS_LMAN_SYM_OUTLINE -50,50,50,-50
J 0
(-2000 5150);
DISPLAY 0.468085 (-2000 5150);
PAINT GREEN (-2000 5150);
DISPLAY INVISIBLE (-2000 5150);
FORCEPROP 1 LAST BODY_TYPE COMMENT
J 0
(-1990 5285);
DISPLAY 0.808511 (-1990 5285);
PAINT GREEN (-1990 5285);
DISPLAY INVISIBLE (-1990 5285);
FORCEPROP 1 LAST OFFPAGE TRUE
J 0
(-1990 5205);
DISPLAY 0.808511 (-1990 5205);
PAINT GREEN (-1990 5205);
DISPLAY INVISIBLE (-1990 5205);
FORCEPROP 2 LAST PATH I39
J 0
(-1900 5200);
DISPLAY 1.021277 (-1900 5200);
DISPLAY INVISIBLE (-1900 5200);
FORCEADD CAPACITOR..2
(-250 5800);
FORCEPROP 1 LAST $LOCATION C37
J 0
(-150 5600);
DISPLAY 1.212766 (-150 5600);
PAINT GREEN (-150 5600);
FORCEPROP 0 LAST CDS_LOCATION C37
J 0
(-200 5950);
DISPLAY 1.021277 (-200 5950);
DISPLAY INVISIBLE (-200 5950);
FORCEPROP 0 LAST $SEC 1
J 0
(-200 5950);
DISPLAY 0.680851 (-200 5950);
PAINT MONO (-200 5950);
DISPLAY INVISIBLE (-200 5950);
FORCEPROP 0 LAST CDS_SEC 1
J 0
(-200 5950);
DISPLAY 1.021277 (-200 5950);
DISPLAY INVISIBLE (-200 5950);
FORCEPROP 0 LASTPIN (-250 5900) $PN 1
R 1
J 0
(-260 5910);
DISPLAY 0.680851 (-260 5910);
PAINT MONO (-260 5910);
FORCEPROP 0 LASTPIN (-250 5650) $PN 2
R 1
J 2
(-260 5640);
DISPLAY 0.680851 (-260 5640);
PAINT MONO (-260 5640);
FORCEPROP 1 LAST VALUE 0.1UF
J 0
(-200 5850);
DISPLAY 1.212766 (-200 5850);
PAINT GREEN (-200 5850);
FORCEPROP 0 LAST VOLTAGE 10V
J 0
(-150 5750);
DISPLAY 1.021277 (-150 5750);
FORCEPROP 0 LAST PACKAGE 0402
J 0
(-150 6000);
DISPLAY 1.021277 (-150 6000);
FORCEPROP 1 LAST TOLERANCE 10%
J 0
(-400 5900);
DISPLAY 1.212766 (-400 5900);
PAINT GREEN (-400 5900);
DISPLAY INVISIBLE (-400 5900);
FORCEPROP 1 LAST CLS_PN G105-0B104-CK
J 0
(-350 5850);
DISPLAY 1.212766 (-350 5850);
PAINT GREEN (-350 5850);
DISPLAY INVISIBLE (-350 5850);
FORCEPROP 1 LAST CDS_LMAN_SYM_OUTLINE -50,0,50,-50
J 0
(-250 5800);
DISPLAY 0.468085 (-250 5800);
PAINT GREEN (-250 5800);
DISPLAY INVISIBLE (-250 5800);
FORCEPROP 2 LAST CDS_LIB passive
J 0
(-250 5800);
DISPLAY INVISIBLE (-250 5800);
FORCEPROP 1 LAST PATH I4
J 0
(-350 5850);
DISPLAY 1.212766 (-350 5850);
PAINT GREEN (-350 5850);
DISPLAY INVISIBLE (-350 5850);
FORCEADD OFFPAGE_IN..2
(-2000 5250);
FORCEPROP 2 LAST $XR0 10D12> 
J 0
(-1945 5250);
DISPLAY 0.638298 (-1945 5250);
PAINT MONO (-1945 5250);
FORCEPROP 2 LAST CDS_LIB cls
J 0
(-2000 5250);
DISPLAY INVISIBLE (-2000 5250);
FORCEPROP 1 LAST CDS_LMAN_SYM_OUTLINE -50,50,50,-50
J 0
(-2000 5250);
DISPLAY 0.468085 (-2000 5250);
PAINT GREEN (-2000 5250);
DISPLAY INVISIBLE (-2000 5250);
FORCEPROP 1 LAST BODY_TYPE COMMENT
J 0
(-1990 5385);
DISPLAY 0.808511 (-1990 5385);
PAINT GREEN (-1990 5385);
DISPLAY INVISIBLE (-1990 5385);
FORCEPROP 1 LAST OFFPAGE TRUE
J 0
(-1990 5305);
DISPLAY 0.808511 (-1990 5305);
PAINT GREEN (-1990 5305);
DISPLAY INVISIBLE (-1990 5305);
FORCEPROP 2 LAST PATH I40
J 0
(-1900 5300);
DISPLAY 1.021277 (-1900 5300);
DISPLAY INVISIBLE (-1900 5300);
FORCEADD OFFPAGE_IN..2
(-2000 5550);
FORCEPROP 2 LAST $XR0 10C12> 
J 0
(-1945 5550);
DISPLAY 0.638298 (-1945 5550);
PAINT MONO (-1945 5550);
FORCEPROP 2 LAST CDS_LIB cls
J 0
(-2000 5550);
DISPLAY INVISIBLE (-2000 5550);
FORCEPROP 1 LAST CDS_LMAN_SYM_OUTLINE -50,50,50,-50
J 0
(-2000 5550);
DISPLAY 0.468085 (-2000 5550);
PAINT GREEN (-2000 5550);
DISPLAY INVISIBLE (-2000 5550);
FORCEPROP 1 LAST BODY_TYPE COMMENT
J 0
(-1990 5685);
DISPLAY 0.808511 (-1990 5685);
PAINT GREEN (-1990 5685);
DISPLAY INVISIBLE (-1990 5685);
FORCEPROP 1 LAST OFFPAGE TRUE
J 0
(-1990 5605);
DISPLAY 0.808511 (-1990 5605);
PAINT GREEN (-1990 5605);
DISPLAY INVISIBLE (-1990 5605);
FORCEPROP 2 LAST PATH I41
J 0
(-1900 5600);
DISPLAY 1.021277 (-1900 5600);
DISPLAY INVISIBLE (-1900 5600);
FORCEADD OFFPAGE_IN..2
(-2000 5650);
FORCEPROP 2 LAST $XR0 10C12> 
J 0
(-1945 5650);
DISPLAY 0.638298 (-1945 5650);
PAINT MONO (-1945 5650);
FORCEPROP 2 LAST CDS_LIB cls
J 0
(-2000 5650);
DISPLAY INVISIBLE (-2000 5650);
FORCEPROP 1 LAST CDS_LMAN_SYM_OUTLINE -50,50,50,-50
J 0
(-2000 5650);
DISPLAY 0.468085 (-2000 5650);
PAINT GREEN (-2000 5650);
DISPLAY INVISIBLE (-2000 5650);
FORCEPROP 1 LAST BODY_TYPE COMMENT
J 0
(-1990 5785);
DISPLAY 0.808511 (-1990 5785);
PAINT GREEN (-1990 5785);
DISPLAY INVISIBLE (-1990 5785);
FORCEPROP 1 LAST OFFPAGE TRUE
J 0
(-1990 5705);
DISPLAY 0.808511 (-1990 5705);
PAINT GREEN (-1990 5705);
DISPLAY INVISIBLE (-1990 5705);
FORCEPROP 2 LAST PATH I42
J 0
(-1900 5700);
DISPLAY 1.021277 (-1900 5700);
DISPLAY INVISIBLE (-1900 5700);
FORCEADD OFFPAGE_IN..2
(-2000 6050);
FORCEPROP 2 LAST $XR0 10C12> 
J 0
(-1945 6050);
DISPLAY 0.638298 (-1945 6050);
PAINT MONO (-1945 6050);
FORCEPROP 2 LAST CDS_LIB cls
J 0
(-2000 6050);
DISPLAY INVISIBLE (-2000 6050);
FORCEPROP 1 LAST CDS_LMAN_SYM_OUTLINE -50,50,50,-50
J 0
(-2000 6050);
DISPLAY 0.468085 (-2000 6050);
PAINT GREEN (-2000 6050);
DISPLAY INVISIBLE (-2000 6050);
FORCEPROP 1 LAST BODY_TYPE COMMENT
J 0
(-1990 6185);
DISPLAY 0.808511 (-1990 6185);
PAINT GREEN (-1990 6185);
DISPLAY INVISIBLE (-1990 6185);
FORCEPROP 1 LAST OFFPAGE TRUE
J 0
(-1990 6105);
DISPLAY 0.808511 (-1990 6105);
PAINT GREEN (-1990 6105);
DISPLAY INVISIBLE (-1990 6105);
FORCEPROP 2 LAST PATH I43
J 0
(-1900 6100);
DISPLAY 1.021277 (-1900 6100);
DISPLAY INVISIBLE (-1900 6100);
FORCEADD OFFPAGE_IN..2
(-2000 5950);
FORCEPROP 2 LAST $XR0 10C12> 
J 0
(-1945 5950);
DISPLAY 0.638298 (-1945 5950);
PAINT MONO (-1945 5950);
FORCEPROP 2 LAST CDS_LIB cls
J 0
(-2000 5950);
DISPLAY INVISIBLE (-2000 5950);
FORCEPROP 1 LAST CDS_LMAN_SYM_OUTLINE -50,50,50,-50
J 0
(-2000 5950);
DISPLAY 0.468085 (-2000 5950);
PAINT GREEN (-2000 5950);
DISPLAY INVISIBLE (-2000 5950);
FORCEPROP 1 LAST BODY_TYPE COMMENT
J 0
(-1990 6085);
DISPLAY 0.808511 (-1990 6085);
PAINT GREEN (-1990 6085);
DISPLAY INVISIBLE (-1990 6085);
FORCEPROP 1 LAST OFFPAGE TRUE
J 0
(-1990 6005);
DISPLAY 0.808511 (-1990 6005);
PAINT GREEN (-1990 6005);
DISPLAY INVISIBLE (-1990 6005);
FORCEPROP 2 LAST PATH I44
J 0
(-1900 6000);
DISPLAY 1.021277 (-1900 6000);
DISPLAY INVISIBLE (-1900 6000);
FORCEADD OFFPAGE_IN..2
(-2000 6550);
FORCEPROP 2 LAST $XR0 10C12> 
J 0
(-1945 6550);
DISPLAY 0.638298 (-1945 6550);
PAINT MONO (-1945 6550);
FORCEPROP 2 LAST CDS_LIB cls
J 0
(-2000 6550);
DISPLAY INVISIBLE (-2000 6550);
FORCEPROP 1 LAST CDS_LMAN_SYM_OUTLINE -50,50,50,-50
J 0
(-2000 6550);
DISPLAY 0.468085 (-2000 6550);
PAINT GREEN (-2000 6550);
DISPLAY INVISIBLE (-2000 6550);
FORCEPROP 1 LAST BODY_TYPE COMMENT
J 0
(-1990 6685);
DISPLAY 0.808511 (-1990 6685);
PAINT GREEN (-1990 6685);
DISPLAY INVISIBLE (-1990 6685);
FORCEPROP 1 LAST OFFPAGE TRUE
J 0
(-1990 6605);
DISPLAY 0.808511 (-1990 6605);
PAINT GREEN (-1990 6605);
DISPLAY INVISIBLE (-1990 6605);
FORCEPROP 2 LAST PATH I45
J 0
(-1900 6600);
DISPLAY 1.021277 (-1900 6600);
DISPLAY INVISIBLE (-1900 6600);
FORCEADD OFFPAGE_IN..2
(-2000 6450);
FORCEPROP 2 LAST $XR0 10C12> 
J 0
(-1945 6450);
DISPLAY 0.638298 (-1945 6450);
PAINT MONO (-1945 6450);
FORCEPROP 2 LAST CDS_LIB cls
J 0
(-2000 6450);
DISPLAY INVISIBLE (-2000 6450);
FORCEPROP 1 LAST CDS_LMAN_SYM_OUTLINE -50,50,50,-50
J 0
(-2000 6450);
DISPLAY 0.468085 (-2000 6450);
PAINT GREEN (-2000 6450);
DISPLAY INVISIBLE (-2000 6450);
FORCEPROP 1 LAST BODY_TYPE COMMENT
J 0
(-1990 6585);
DISPLAY 0.808511 (-1990 6585);
PAINT GREEN (-1990 6585);
DISPLAY INVISIBLE (-1990 6585);
FORCEPROP 1 LAST OFFPAGE TRUE
J 0
(-1990 6505);
DISPLAY 0.808511 (-1990 6505);
PAINT GREEN (-1990 6505);
DISPLAY INVISIBLE (-1990 6505);
FORCEPROP 2 LAST PATH I46
J 0
(-1900 6500);
DISPLAY 1.021277 (-1900 6500);
DISPLAY INVISIBLE (-1900 6500);
FORCEADD OFFPAGE_OUT..1
(-2000 6850);
FORCEPROP 2 LAST $XR0 10D5< 
J 0
(-1945 6850);
DISPLAY 0.638298 (-1945 6850);
PAINT MONO (-1945 6850);
FORCEPROP 1 LAST CDS_LMAN_SYM_OUTLINE -50,50,50,-50
J 0
(-2000 6850);
DISPLAY 0.468085 (-2000 6850);
PAINT GREEN (-2000 6850);
DISPLAY INVISIBLE (-2000 6850);
FORCEPROP 2 LAST CDS_LIB cls
J 0
(-2000 6850);
DISPLAY INVISIBLE (-2000 6850);
FORCEPROP 2 LAST PATH I47
J 0
(-1900 6900);
DISPLAY 1.021277 (-1900 6900);
DISPLAY INVISIBLE (-1900 6900);
FORCEPROP 1 LAST OFFPAGE TRUE
J 0
(-1990 6905);
DISPLAY 0.808511 (-1990 6905);
PAINT GREEN (-1990 6905);
DISPLAY INVISIBLE (-1990 6905);
FORCEPROP 1 LAST BODY_TYPE COMMENT
J 0
(-1990 6985);
DISPLAY 0.808511 (-1990 6985);
PAINT GREEN (-1990 6985);
DISPLAY INVISIBLE (-1990 6985);
FORCEADD OFFPAGE_OUT..1
(-2000 6750);
FORCEPROP 2 LAST $XR0 10D5< 
J 0
(-1945 6750);
DISPLAY 0.638298 (-1945 6750);
PAINT MONO (-1945 6750);
FORCEPROP 2 LAST CDS_LIB cls
J 0
(-2000 6750);
DISPLAY INVISIBLE (-2000 6750);
FORCEPROP 1 LAST CDS_LMAN_SYM_OUTLINE -50,50,50,-50
J 0
(-2000 6750);
DISPLAY 0.468085 (-2000 6750);
PAINT GREEN (-2000 6750);
DISPLAY INVISIBLE (-2000 6750);
FORCEPROP 1 LAST BODY_TYPE COMMENT
J 0
(-1990 6885);
DISPLAY 0.808511 (-1990 6885);
PAINT GREEN (-1990 6885);
DISPLAY INVISIBLE (-1990 6885);
FORCEPROP 1 LAST OFFPAGE TRUE
J 0
(-1990 6805);
DISPLAY 0.808511 (-1990 6805);
PAINT GREEN (-1990 6805);
DISPLAY INVISIBLE (-1990 6805);
FORCEPROP 2 LAST PATH I48
J 0
(-1900 6800);
DISPLAY 1.021277 (-1900 6800);
DISPLAY INVISIBLE (-1900 6800);
FORCEADD VCC..1
(-5550 8850);
FORCEPROP 3 LASTPIN (-5500 8800) SIG_NAME XP3R3V_PCIE\g
J 0
(-5490 8810);
DISPLAY 0.659574 (-5490 8810);
PAINT MONO (-5490 8810);
DISPLAY INVISIBLE (-5490 8810);
FORCEPROP 0 LAST VOLTAGE 3.3
J 1
(-5500 8950);
DISPLAY 1.021277 (-5500 8950);
DISPLAY BOTH (-5500 8950);
FORCEPROP 1 LAST HDL_POWER XP3R3V_PCIE
J 1
(-5500 8900);
DISPLAY 0.808511 (-5500 8900);
PAINT GREEN (-5500 8900);
FORCEPROP 1 LAST PATH I49
J 0
(-5515 8940);
DISPLAY 0.808511 (-5515 8940);
PAINT GREEN (-5515 8940);
DISPLAY INVISIBLE (-5515 8940);
FORCEPROP 1 LAST BODY_TYPE PLUMBING
J 0
(-5595 8807);
DISPLAY 0.340426 (-5595 8807);
PAINT GREEN (-5595 8807);
DISPLAY INVISIBLE (-5595 8807);
FORCEPROP 2 LAST CDS_LIB cls
J 0
(-5550 8850);
DISPLAY INVISIBLE (-5550 8850);
FORCEPROP 1 LAST CDS_LMAN_SYM_OUTLINE -250,250,250,-250
J 0
(-5550 8850);
DISPLAY 0.468085 (-5550 8850);
PAINT GREEN (-5550 8850);
DISPLAY INVISIBLE (-5550 8850);
FORCEADD OFFPAGE_OUT..1
R 2
(-9650 5350);
FORCEPROP 2 LAST $XR0 10D5< 
J 0
(-9833 5350);
DISPLAY 0.638298 (-9833 5350);
PAINT MONO (-9833 5350);
FORCEPROP 2 LAST CDS_LIB cls
J 0
(-9650 5350);
DISPLAY INVISIBLE (-9650 5350);
FORCEPROP 1 LAST CDS_LMAN_SYM_OUTLINE -50,50,50,-50
J 2
(-9650 5350);
DISPLAY 0.468085 (-9650 5350);
PAINT GREEN (-9650 5350);
DISPLAY INVISIBLE (-9650 5350);
FORCEPROP 1 LAST BODY_TYPE COMMENT
J 2
(-9660 5485);
DISPLAY 0.808511 (-9660 5485);
PAINT GREEN (-9660 5485);
DISPLAY INVISIBLE (-9660 5485);
FORCEPROP 1 LAST OFFPAGE TRUE
J 2
(-9660 5405);
DISPLAY 0.808511 (-9660 5405);
PAINT GREEN (-9660 5405);
DISPLAY INVISIBLE (-9660 5405);
FORCEPROP 2 LAST PATH I5
J 0
(-9800 5400);
DISPLAY 1.021277 (-9800 5400);
DISPLAY INVISIBLE (-9800 5400);
FORCEADD RESISTOR..1
(-3950 7450);
FORCEPROP 1 LAST $LOCATION R43
J 2
(-4150 7450);
DISPLAY 1.212766 (-4150 7450);
PAINT GREEN (-4150 7450);
FORCEPROP 0 LAST CDS_LOCATION R43
J 0
(-3700 7550);
DISPLAY 1.021277 (-3700 7550);
DISPLAY INVISIBLE (-3700 7550);
FORCEPROP 0 LAST $SEC 1
J 0
(-3700 7550);
DISPLAY 0.680851 (-3700 7550);
PAINT MONO (-3700 7550);
DISPLAY INVISIBLE (-3700 7550);
FORCEPROP 0 LAST CDS_SEC 1
J 0
(-3700 7550);
DISPLAY 1.021277 (-3700 7550);
DISPLAY INVISIBLE (-3700 7550);
FORCEPROP 0 LASTPIN (-4050 7450) $PN 1
J 2
(-4060 7460);
DISPLAY 0.680851 (-4060 7460);
PAINT MONO (-4060 7460);
FORCEPROP 0 LASTPIN (-3800 7450) $PN 2
J 0
(-3790 7460);
DISPLAY 0.680851 (-3790 7460);
PAINT MONO (-3790 7460);
FORCEPROP 0 LAST PACKAGE 0402
J 0
(-3450 7450);
DISPLAY 0.808511 (-3450 7450);
FORCEPROP 0 LAST NO_ASSY TRUE
J 0
(-4050 7450);
DISPLAY 0.808511 (-4050 7450);
DISPLAY BOTH (-4050 7450);
FORCEPROP 1 LAST VALUE 0OHM
J 0
(-3700 7450);
DISPLAY 1.212766 (-3700 7450);
PAINT GREEN (-3700 7450);
FORCEPROP 1 LAST CDS_LMAN_SYM_OUTLINE -50,50,100,-50
J 0
(-3950 7450);
DISPLAY 0.468085 (-3950 7450);
PAINT GREEN (-3950 7450);
DISPLAY INVISIBLE (-3950 7450);
FORCEPROP 2 LAST CDS_LIB passive
J 0
(-3950 7450);
DISPLAY INVISIBLE (-3950 7450);
FORCEPROP 1 LAST CLS_PN G155-100R0-J0
J 0
(-4086 7650);
DISPLAY 1.212766 (-4086 7650);
PAINT GREEN (-4086 7650);
DISPLAY INVISIBLE (-4086 7650);
FORCEPROP 1 LAST TOLERANCE -
J 0
(-4147 7705);
DISPLAY 1.212766 (-4147 7705);
PAINT GREEN (-4147 7705);
DISPLAY INVISIBLE (-4147 7705);
FORCEPROP 1 LAST PATH I51
J 0
(-4147 7555);
DISPLAY 1.212766 (-4147 7555);
PAINT GREEN (-4147 7555);
DISPLAY INVISIBLE (-4147 7555);
FORCEADD RESISTOR..1
(-3950 7550);
FORCEPROP 1 LAST $LOCATION R42
J 2
(-4150 7550);
DISPLAY 1.212766 (-4150 7550);
PAINT GREEN (-4150 7550);
FORCEPROP 0 LAST CDS_LOCATION R42
J 0
(-3700 7650);
DISPLAY 1.021277 (-3700 7650);
DISPLAY INVISIBLE (-3700 7650);
FORCEPROP 0 LAST $SEC 1
J 0
(-3700 7650);
DISPLAY 0.680851 (-3700 7650);
PAINT MONO (-3700 7650);
DISPLAY INVISIBLE (-3700 7650);
FORCEPROP 0 LAST CDS_SEC 1
J 0
(-3700 7650);
DISPLAY 1.021277 (-3700 7650);
DISPLAY INVISIBLE (-3700 7650);
FORCEPROP 0 LASTPIN (-4050 7550) $PN 1
J 2
(-4060 7560);
DISPLAY 0.680851 (-4060 7560);
PAINT MONO (-4060 7560);
FORCEPROP 0 LASTPIN (-3800 7550) $PN 2
J 0
(-3790 7560);
DISPLAY 0.680851 (-3790 7560);
PAINT MONO (-3790 7560);
FORCEPROP 0 LAST NO_ASSY TRUE
J 0
(-4050 7550);
DISPLAY 0.808511 (-4050 7550);
DISPLAY BOTH (-4050 7550);
FORCEPROP 0 LAST PACKAGE 0402
J 0
(-3450 7550);
DISPLAY 0.808511 (-3450 7550);
FORCEPROP 1 LAST VALUE 0OHM
J 0
(-3700 7550);
DISPLAY 1.212766 (-3700 7550);
PAINT GREEN (-3700 7550);
FORCEPROP 2 LAST CDS_LIB passive
J 0
(-3950 7550);
DISPLAY INVISIBLE (-3950 7550);
FORCEPROP 1 LAST CDS_LMAN_SYM_OUTLINE -50,50,100,-50
J 0
(-3950 7550);
DISPLAY 0.468085 (-3950 7550);
PAINT GREEN (-3950 7550);
DISPLAY INVISIBLE (-3950 7550);
FORCEPROP 1 LAST CLS_PN G155-100R0-J0
J 0
(-4086 7750);
DISPLAY 1.212766 (-4086 7750);
PAINT GREEN (-4086 7750);
DISPLAY INVISIBLE (-4086 7750);
FORCEPROP 1 LAST TOLERANCE -
J 0
(-4147 7805);
DISPLAY 1.212766 (-4147 7805);
PAINT GREEN (-4147 7805);
DISPLAY INVISIBLE (-4147 7805);
FORCEPROP 1 LAST PATH I52
J 0
(-4147 7655);
DISPLAY 1.212766 (-4147 7655);
PAINT GREEN (-4147 7655);
DISPLAY INVISIBLE (-4147 7655);
FORCEADD RESISTOR..1
(-3950 7650);
FORCEPROP 1 LAST $LOCATION R41
J 2
(-4150 7650);
DISPLAY 1.212766 (-4150 7650);
PAINT GREEN (-4150 7650);
FORCEPROP 0 LAST CDS_LOCATION R41
J 0
(-3700 7750);
DISPLAY 1.021277 (-3700 7750);
DISPLAY INVISIBLE (-3700 7750);
FORCEPROP 0 LAST $SEC 1
J 0
(-3700 7750);
DISPLAY 0.680851 (-3700 7750);
PAINT MONO (-3700 7750);
DISPLAY INVISIBLE (-3700 7750);
FORCEPROP 0 LAST CDS_SEC 1
J 0
(-3700 7750);
DISPLAY 1.021277 (-3700 7750);
DISPLAY INVISIBLE (-3700 7750);
FORCEPROP 0 LASTPIN (-4050 7650) $PN 1
J 2
(-4060 7660);
DISPLAY 0.680851 (-4060 7660);
PAINT MONO (-4060 7660);
FORCEPROP 0 LASTPIN (-3800 7650) $PN 2
J 0
(-3790 7660);
DISPLAY 0.680851 (-3790 7660);
PAINT MONO (-3790 7660);
FORCEPROP 0 LAST PACKAGE 0402
J 0
(-3450 7650);
DISPLAY 0.808511 (-3450 7650);
FORCEPROP 0 LAST NO_ASSY TRUE
J 0
(-4050 7650);
DISPLAY 0.808511 (-4050 7650);
DISPLAY BOTH (-4050 7650);
FORCEPROP 1 LAST VALUE 0OHM
J 0
(-3700 7650);
DISPLAY 1.212766 (-3700 7650);
PAINT GREEN (-3700 7650);
FORCEPROP 1 LAST CLS_PN G155-100R0-J0
J 0
(-4086 7850);
DISPLAY 1.212766 (-4086 7850);
PAINT GREEN (-4086 7850);
DISPLAY INVISIBLE (-4086 7850);
FORCEPROP 1 LAST CDS_LMAN_SYM_OUTLINE -50,50,100,-50
J 0
(-3950 7650);
DISPLAY 0.468085 (-3950 7650);
PAINT GREEN (-3950 7650);
DISPLAY INVISIBLE (-3950 7650);
FORCEPROP 2 LAST CDS_LIB passive
J 0
(-3950 7650);
DISPLAY INVISIBLE (-3950 7650);
FORCEPROP 1 LAST TOLERANCE -
J 0
(-4147 7905);
DISPLAY 1.212766 (-4147 7905);
PAINT GREEN (-4147 7905);
DISPLAY INVISIBLE (-4147 7905);
FORCEPROP 1 LAST PATH I53
J 0
(-4147 7755);
DISPLAY 1.212766 (-4147 7755);
PAINT GREEN (-4147 7755);
DISPLAY INVISIBLE (-4147 7755);
FORCEADD RESISTOR..1
(-3950 7750);
FORCEPROP 1 LAST $LOCATION R28
J 2
(-4150 7750);
DISPLAY 1.212766 (-4150 7750);
PAINT GREEN (-4150 7750);
FORCEPROP 0 LAST CDS_LOCATION R28
J 0
(-3700 7850);
DISPLAY 1.021277 (-3700 7850);
DISPLAY INVISIBLE (-3700 7850);
FORCEPROP 0 LAST $SEC 1
J 0
(-3700 7850);
DISPLAY 0.680851 (-3700 7850);
PAINT MONO (-3700 7850);
DISPLAY INVISIBLE (-3700 7850);
FORCEPROP 0 LAST CDS_SEC 1
J 0
(-3700 7850);
DISPLAY 1.021277 (-3700 7850);
DISPLAY INVISIBLE (-3700 7850);
FORCEPROP 0 LASTPIN (-4050 7750) $PN 1
J 2
(-4060 7760);
DISPLAY 0.680851 (-4060 7760);
PAINT MONO (-4060 7760);
FORCEPROP 0 LASTPIN (-3800 7750) $PN 2
J 0
(-3790 7760);
DISPLAY 0.680851 (-3790 7760);
PAINT MONO (-3790 7760);
FORCEPROP 0 LAST PACKAGE 0402
J 0
(-3450 7750);
DISPLAY 0.808511 (-3450 7750);
FORCEPROP 0 LAST NO_ASSY TRUE
J 0
(-4050 7750);
DISPLAY 0.808511 (-4050 7750);
DISPLAY BOTH (-4050 7750);
FORCEPROP 1 LAST VALUE 0OHM
J 0
(-3700 7750);
DISPLAY 1.212766 (-3700 7750);
PAINT GREEN (-3700 7750);
FORCEPROP 1 LAST CLS_PN G155-100R0-J0
J 0
(-4086 7950);
DISPLAY 1.212766 (-4086 7950);
PAINT GREEN (-4086 7950);
DISPLAY INVISIBLE (-4086 7950);
FORCEPROP 1 LAST CDS_LMAN_SYM_OUTLINE -50,50,100,-50
J 0
(-3950 7750);
DISPLAY 0.468085 (-3950 7750);
PAINT GREEN (-3950 7750);
DISPLAY INVISIBLE (-3950 7750);
FORCEPROP 2 LAST CDS_LIB passive
J 0
(-3950 7750);
DISPLAY INVISIBLE (-3950 7750);
FORCEPROP 1 LAST TOLERANCE -
J 0
(-4147 8005);
DISPLAY 1.212766 (-4147 8005);
PAINT GREEN (-4147 8005);
DISPLAY INVISIBLE (-4147 8005);
FORCEPROP 1 LAST PATH I54
J 0
(-4147 7855);
DISPLAY 1.212766 (-4147 7855);
PAINT GREEN (-4147 7855);
DISPLAY INVISIBLE (-4147 7855);
FORCEADD OFFPAGE_IN..2
(-4400 8150);
FORCEPROP 2 LAST $XR0 9E3< 
J 0
(-4345 8150);
DISPLAY 0.638298 (-4345 8150);
PAINT MONO (-4345 8150);
FORCEPROP 2 LAST $XR1 9G3< 
J 0
(-4195 8150);
DISPLAY 0.638298 (-4195 8150);
PAINT MONO (-4195 8150);
FORCEPROP 1 LAST BODY_TYPE COMMENT
J 0
(-4390 8285);
DISPLAY 0.808511 (-4390 8285);
PAINT GREEN (-4390 8285);
DISPLAY INVISIBLE (-4390 8285);
FORCEPROP 1 LAST CDS_LMAN_SYM_OUTLINE -50,50,50,-50
J 0
(-4400 8150);
DISPLAY 0.468085 (-4400 8150);
PAINT GREEN (-4400 8150);
DISPLAY INVISIBLE (-4400 8150);
FORCEPROP 2 LAST CDS_LIB cls
J 0
(-4400 8150);
DISPLAY INVISIBLE (-4400 8150);
FORCEPROP 1 LAST OFFPAGE TRUE
J 0
(-4390 8205);
DISPLAY 0.808511 (-4390 8205);
PAINT GREEN (-4390 8205);
DISPLAY INVISIBLE (-4390 8205);
FORCEPROP 2 LAST PATH I55
J 0
(-4300 8200);
DISPLAY 1.021277 (-4300 8200);
DISPLAY INVISIBLE (-4300 8200);
FORCEADD OFFPAGE_OUT..1
(-2500 7450);
FORCEPROP 2 LAST $XR1 10F5< 
J 0
(-2265 7450);
DISPLAY 0.638298 (-2265 7450);
PAINT MONO (-2265 7450);
FORCEPROP 2 LAST $XR0 10J7> 
J 0
(-2445 7450);
DISPLAY 0.638298 (-2445 7450);
PAINT MONO (-2445 7450);
FORCEPROP 1 LAST BODY_TYPE COMMENT
J 0
(-2490 7585);
DISPLAY 0.808511 (-2490 7585);
PAINT GREEN (-2490 7585);
DISPLAY INVISIBLE (-2490 7585);
FORCEPROP 1 LAST CDS_LMAN_SYM_OUTLINE -50,50,50,-50
J 0
(-2500 7450);
DISPLAY 0.468085 (-2500 7450);
PAINT GREEN (-2500 7450);
DISPLAY INVISIBLE (-2500 7450);
FORCEPROP 2 LAST CDS_LIB cls
J 0
(-2500 7450);
DISPLAY INVISIBLE (-2500 7450);
FORCEPROP 1 LAST OFFPAGE TRUE
J 0
(-2490 7505);
DISPLAY 0.808511 (-2490 7505);
PAINT GREEN (-2490 7505);
DISPLAY INVISIBLE (-2490 7505);
FORCEPROP 2 LAST PATH I56
J 0
(-2400 7500);
DISPLAY 1.021277 (-2400 7500);
DISPLAY INVISIBLE (-2400 7500);
FORCEADD OFFPAGE_IN..2
(-2500 7550);
FORCEPROP 2 LAST $XR0 10E5> 
J 0
(-2445 7550);
DISPLAY 0.638298 (-2445 7550);
PAINT MONO (-2445 7550);
FORCEPROP 2 LAST $XR1 10J7< 
J 0
(-2265 7550);
DISPLAY 0.638298 (-2265 7550);
PAINT MONO (-2265 7550);
FORCEPROP 2 LAST CDS_LIB cls
J 0
(-2500 7550);
DISPLAY INVISIBLE (-2500 7550);
FORCEPROP 1 LAST CDS_LMAN_SYM_OUTLINE -50,50,50,-50
J 0
(-2500 7550);
DISPLAY 0.468085 (-2500 7550);
PAINT GREEN (-2500 7550);
DISPLAY INVISIBLE (-2500 7550);
FORCEPROP 1 LAST BODY_TYPE COMMENT
J 0
(-2490 7685);
DISPLAY 0.808511 (-2490 7685);
PAINT GREEN (-2490 7685);
DISPLAY INVISIBLE (-2490 7685);
FORCEPROP 1 LAST OFFPAGE TRUE
J 0
(-2490 7605);
DISPLAY 0.808511 (-2490 7605);
PAINT GREEN (-2490 7605);
DISPLAY INVISIBLE (-2490 7605);
FORCEPROP 2 LAST PATH I57
J 0
(-2400 7600);
DISPLAY 1.021277 (-2400 7600);
DISPLAY INVISIBLE (-2400 7600);
FORCEADD OFFPAGE_OUT..1
(-2500 7650);
FORCEPROP 2 LAST $XR0 10K7> 
J 0
(-2445 7650);
DISPLAY 0.638298 (-2445 7650);
PAINT MONO (-2445 7650);
FORCEPROP 2 LAST $XR1 10E5< 
J 0
(-2265 7650);
DISPLAY 0.638298 (-2265 7650);
PAINT MONO (-2265 7650);
FORCEPROP 1 LAST BODY_TYPE COMMENT
J 0
(-2490 7785);
DISPLAY 0.808511 (-2490 7785);
PAINT GREEN (-2490 7785);
DISPLAY INVISIBLE (-2490 7785);
FORCEPROP 1 LAST CDS_LMAN_SYM_OUTLINE -50,50,50,-50
J 0
(-2500 7650);
DISPLAY 0.468085 (-2500 7650);
PAINT GREEN (-2500 7650);
DISPLAY INVISIBLE (-2500 7650);
FORCEPROP 2 LAST CDS_LIB cls
J 0
(-2500 7650);
DISPLAY INVISIBLE (-2500 7650);
FORCEPROP 1 LAST OFFPAGE TRUE
J 0
(-2490 7705);
DISPLAY 0.808511 (-2490 7705);
PAINT GREEN (-2490 7705);
DISPLAY INVISIBLE (-2490 7705);
FORCEPROP 2 LAST PATH I58
J 0
(-2400 7700);
DISPLAY 1.021277 (-2400 7700);
DISPLAY INVISIBLE (-2400 7700);
FORCEADD OFFPAGE_OUT..1
(-2500 7750);
FORCEPROP 2 LAST $XR0 10J7> 
J 0
(-2445 7750);
DISPLAY 0.638298 (-2445 7750);
PAINT MONO (-2445 7750);
FORCEPROP 2 LAST $XR1 10E5< 
J 0
(-2265 7750);
DISPLAY 0.638298 (-2265 7750);
PAINT MONO (-2265 7750);
FORCEPROP 1 LAST BODY_TYPE COMMENT
J 0
(-2490 7885);
DISPLAY 0.808511 (-2490 7885);
PAINT GREEN (-2490 7885);
DISPLAY INVISIBLE (-2490 7885);
FORCEPROP 1 LAST CDS_LMAN_SYM_OUTLINE -50,50,50,-50
J 0
(-2500 7750);
DISPLAY 0.468085 (-2500 7750);
PAINT GREEN (-2500 7750);
DISPLAY INVISIBLE (-2500 7750);
FORCEPROP 2 LAST CDS_LIB cls
J 0
(-2500 7750);
DISPLAY INVISIBLE (-2500 7750);
FORCEPROP 1 LAST OFFPAGE TRUE
J 0
(-2490 7805);
DISPLAY 0.808511 (-2490 7805);
PAINT GREEN (-2490 7805);
DISPLAY INVISIBLE (-2490 7805);
FORCEPROP 2 LAST PATH I59
J 0
(-2400 7800);
DISPLAY 1.021277 (-2400 7800);
DISPLAY INVISIBLE (-2400 7800);
FORCEADD OFFPAGE_IN..1
(-9650 5050);
FORCEPROP 2 LAST $XR1 9E3< 
J 0
(-9952 5050);
DISPLAY 0.638298 (-9952 5050);
PAINT MONO (-9952 5050);
FORCEPROP 2 LAST $XR0 9D8< 
J 0
(-9802 5050);
DISPLAY 0.638298 (-9802 5050);
PAINT MONO (-9802 5050);
FORCEPROP 1 LAST CDS_LMAN_SYM_OUTLINE -50,50,50,-50
J 0
(-9650 5050);
DISPLAY 0.468085 (-9650 5050);
PAINT GREEN (-9650 5050);
DISPLAY INVISIBLE (-9650 5050);
FORCEPROP 2 LAST CDS_LIB cls
J 0
(-9650 5050);
DISPLAY INVISIBLE (-9650 5050);
FORCEPROP 2 LAST PATH I6
J 0
(-9800 5100);
DISPLAY 1.021277 (-9800 5100);
DISPLAY INVISIBLE (-9800 5100);
FORCEPROP 1 LAST BODY_TYPE COMMENT
J 0
(-9640 5185);
DISPLAY 0.808511 (-9640 5185);
PAINT GREEN (-9640 5185);
DISPLAY INVISIBLE (-9640 5185);
FORCEPROP 1 LAST OFFPAGE TRUE
J 0
(-9640 5105);
DISPLAY 0.808511 (-9640 5105);
PAINT GREEN (-9640 5105);
DISPLAY INVISIBLE (-9640 5105);
FORCEADD CONN_64P_GF..1
(-7050 8350);
FORCEPROP 2 LASTPIN (-7150 5050) SIG_NAME UN$3$CONN64PGF$I61$PRSNT22
J 0
(-7140 5060);
DISPLAY 0.659574 (-7140 5060);
PAINT MONO (-7140 5060);
DISPLAY INVISIBLE (-7140 5060);
FORCEPROP 2 LASTPIN (-7150 6450) SIG_NAME UN$3$CONN64PGF$I61$PRSNT21
J 0
(-7140 6460);
DISPLAY 0.659574 (-7140 6460);
PAINT MONO (-7140 6460);
DISPLAY INVISIBLE (-7140 6460);
FORCEPROP 1 LAST $LOCATION GF1
J 0
(-7100 8400);
DISPLAY 1.212766 (-7100 8400);
PAINT GREEN (-7100 8400);
FORCEPROP 0 LAST CDS_LOCATION GF1
J 0
(-7100 8600);
DISPLAY 1.021277 (-7100 8600);
DISPLAY INVISIBLE (-7100 8600);
FORCEPROP 0 LAST $SEC 1
J 0
(-7100 8600);
DISPLAY 0.680851 (-7100 8600);
PAINT MONO (-7100 8600);
DISPLAY INVISIBLE (-7100 8600);
FORCEPROP 0 LAST CDS_SEC 1
J 0
(-7100 8600);
DISPLAY 1.021277 (-7100 8600);
DISPLAY INVISIBLE (-7100 8600);
FORCEPROP 0 LASTPIN (-7150 7850) $PN B4
J 2
(-7160 7860);
DISPLAY 0.680851 (-7160 7860);
PAINT MONO (-7160 7860);
FORCEPROP 0 LASTPIN (-5850 7850) $PN A4
J 0
(-5840 7860);
DISPLAY 0.680851 (-5840 7860);
PAINT MONO (-5840 7860);
FORCEPROP 0 LASTPIN (-7150 7550) $PN B7
J 2
(-7160 7560);
DISPLAY 0.680851 (-7160 7560);
PAINT MONO (-7160 7560);
FORCEPROP 0 LASTPIN (-5850 6950) $PN A12
J 0
(-5840 6960);
DISPLAY 0.680851 (-5840 6960);
PAINT MONO (-5840 6960);
FORCEPROP 0 LASTPIN (-7150 6850) $PN B13
J 2
(-7160 6860);
DISPLAY 0.680851 (-7160 6860);
PAINT MONO (-7160 6860);
FORCEPROP 0 LASTPIN (-5850 6650) $PN A15
J 0
(-5840 6660);
DISPLAY 0.680851 (-5840 6660);
PAINT MONO (-5840 6660);
FORCEPROP 0 LASTPIN (-7150 6550) $PN B16
J 2
(-7160 6560);
DISPLAY 0.680851 (-7160 6560);
PAINT MONO (-7160 6560);
FORCEPROP 0 LASTPIN (-5850 6350) $PN A18
J 0
(-5840 6360);
DISPLAY 0.680851 (-5840 6360);
PAINT MONO (-5840 6360);
FORCEPROP 0 LASTPIN (-7150 6350) $PN B18
J 2
(-7160 6360);
DISPLAY 0.680851 (-7160 6360);
PAINT MONO (-7160 6360);
FORCEPROP 0 LASTPIN (-5850 6150) $PN A20
J 0
(-5840 6160);
DISPLAY 0.680851 (-5840 6160);
PAINT MONO (-5840 6160);
FORCEPROP 0 LASTPIN (-7150 6050) $PN B21
J 2
(-7160 6060);
DISPLAY 0.680851 (-7160 6060);
PAINT MONO (-7160 6060);
FORCEPROP 0 LASTPIN (-7150 5950) $PN B22
J 2
(-7160 5960);
DISPLAY 0.680851 (-7160 5960);
PAINT MONO (-7160 5960);
FORCEPROP 0 LASTPIN (-5850 5850) $PN A23
J 0
(-5840 5860);
DISPLAY 0.680851 (-5840 5860);
PAINT MONO (-5840 5860);
FORCEPROP 0 LASTPIN (-5850 5750) $PN A24
J 0
(-5840 5760);
DISPLAY 0.680851 (-5840 5760);
PAINT MONO (-5840 5760);
FORCEPROP 0 LASTPIN (-7150 5650) $PN B25
J 2
(-7160 5660);
DISPLAY 0.680851 (-7160 5660);
PAINT MONO (-7160 5660);
FORCEPROP 0 LASTPIN (-7150 5550) $PN B26
J 2
(-7160 5560);
DISPLAY 0.680851 (-7160 5560);
PAINT MONO (-7160 5560);
FORCEPROP 0 LASTPIN (-5850 5450) $PN A27
J 0
(-5840 5460);
DISPLAY 0.680851 (-5840 5460);
PAINT MONO (-5840 5460);
FORCEPROP 0 LASTPIN (-5850 5350) $PN A28
J 0
(-5840 5360);
DISPLAY 0.680851 (-5840 5360);
PAINT MONO (-5840 5360);
FORCEPROP 0 LASTPIN (-7150 5250) $PN B29
J 2
(-7160 5260);
DISPLAY 0.680851 (-7160 5260);
PAINT MONO (-7160 5260);
FORCEPROP 0 LASTPIN (-5850 5050) $PN A31
J 0
(-5840 5060);
DISPLAY 0.680851 (-5840 5060);
PAINT MONO (-5840 5060);
FORCEPROP 0 LASTPIN (-7150 4950) $PN B32
J 2
(-7160 4960);
DISPLAY 0.680851 (-7160 4960);
PAINT MONO (-7160 4960);
FORCEPROP 0 LASTPIN (-7150 7350) $PN B9
J 2
(-7160 7360);
DISPLAY 0.680851 (-7160 7360);
PAINT MONO (-7160 7360);
FORCEPROP 0 LASTPIN (-5850 7750) $PN A5
J 0
(-5840 7760);
DISPLAY 0.680851 (-5840 7760);
PAINT MONO (-5840 7760);
FORCEPROP 0 LASTPIN (-5850 7650) $PN A6
J 0
(-5840 7660);
DISPLAY 0.680851 (-5840 7660);
PAINT MONO (-5840 7660);
FORCEPROP 0 LASTPIN (-5850 7550) $PN A7
J 0
(-5840 7560);
DISPLAY 0.680851 (-5840 7560);
PAINT MONO (-5840 7560);
FORCEPROP 0 LASTPIN (-5850 7450) $PN A8
J 0
(-5840 7460);
DISPLAY 0.680851 (-5840 7460);
PAINT MONO (-5840 7460);
FORCEPROP 0 LASTPIN (-7150 7450) $PN B8
J 2
(-7160 7460);
DISPLAY 0.680851 (-7160 7460);
PAINT MONO (-7160 7460);
FORCEPROP 0 LASTPIN (-5850 7350) $PN A9
J 0
(-5840 7360);
DISPLAY 0.680851 (-5840 7360);
PAINT MONO (-5840 7360);
FORCEPROP 0 LASTPIN (-5850 7250) $PN A10
J 0
(-5840 7260);
DISPLAY 0.680851 (-5840 7260);
PAINT MONO (-5840 7260);
FORCEPROP 0 LASTPIN (-7150 7250) $PN B10
J 2
(-7160 7260);
DISPLAY 0.680851 (-7160 7260);
PAINT MONO (-7160 7260);
FORCEPROP 0 LASTPIN (-7150 8150) $PN B1
J 2
(-7160 8160);
DISPLAY 0.680851 (-7160 8160);
PAINT MONO (-7160 8160);
FORCEPROP 0 LASTPIN (-7150 8050) $PN B2
J 2
(-7160 8060);
DISPLAY 0.680851 (-7160 8060);
PAINT MONO (-7160 8060);
FORCEPROP 0 LASTPIN (-5850 8050) $PN A2
J 0
(-5840 8060);
DISPLAY 0.680851 (-5840 8060);
PAINT MONO (-5840 8060);
FORCEPROP 0 LASTPIN (-7150 7950) $PN B3
J 2
(-7160 7960);
DISPLAY 0.680851 (-7160 7960);
PAINT MONO (-7160 7960);
FORCEPROP 0 LASTPIN (-5850 7950) $PN A3
J 0
(-5840 7960);
DISPLAY 0.680851 (-5840 7960);
PAINT MONO (-5840 7960);
FORCEPROP 0 LASTPIN (-5850 6450) $PN A17
J 0
(-5840 6460);
DISPLAY 0.680851 (-5840 6460);
PAINT MONO (-5840 6460);
FORCEPROP 0 LASTPIN (-5850 5950) $PN A22
J 0
(-5840 5960);
DISPLAY 0.680851 (-5840 5960);
PAINT MONO (-5840 5960);
FORCEPROP 0 LASTPIN (-5850 5550) $PN A26
J 0
(-5840 5560);
DISPLAY 0.680851 (-5840 5560);
PAINT MONO (-5840 5560);
FORCEPROP 0 LASTPIN (-5850 5150) $PN A30
J 0
(-5840 5160);
DISPLAY 0.680851 (-5840 5160);
PAINT MONO (-5840 5160);
FORCEPROP 0 LASTPIN (-5850 6550) $PN A16
J 0
(-5840 6560);
DISPLAY 0.680851 (-5840 6560);
PAINT MONO (-5840 6560);
FORCEPROP 0 LASTPIN (-5850 6050) $PN A21
J 0
(-5840 6060);
DISPLAY 0.680851 (-5840 6060);
PAINT MONO (-5840 6060);
FORCEPROP 0 LASTPIN (-5850 5650) $PN A25
J 0
(-5840 5660);
DISPLAY 0.680851 (-5840 5660);
PAINT MONO (-5840 5660);
FORCEPROP 0 LASTPIN (-5850 5250) $PN A29
J 0
(-5840 5260);
DISPLAY 0.680851 (-5840 5260);
PAINT MONO (-5840 5260);
FORCEPROP 0 LASTPIN (-5850 7150) $PN A11
J 0
(-5840 7160);
DISPLAY 0.680851 (-5840 7160);
PAINT MONO (-5840 7160);
FORCEPROP 0 LASTPIN (-7150 6650) $PN B15
J 2
(-7160 6660);
DISPLAY 0.680851 (-7160 6660);
PAINT MONO (-7160 6660);
FORCEPROP 0 LASTPIN (-7150 6150) $PN B20
J 2
(-7160 6160);
DISPLAY 0.680851 (-7160 6160);
PAINT MONO (-7160 6160);
FORCEPROP 0 LASTPIN (-7150 5750) $PN B24
J 2
(-7160 5760);
DISPLAY 0.680851 (-7160 5760);
PAINT MONO (-7160 5760);
FORCEPROP 0 LASTPIN (-7150 5350) $PN B28
J 2
(-7160 5360);
DISPLAY 0.680851 (-7160 5360);
PAINT MONO (-7160 5360);
FORCEPROP 0 LASTPIN (-7150 6750) $PN B14
J 2
(-7160 6760);
DISPLAY 0.680851 (-7160 6760);
PAINT MONO (-7160 6760);
FORCEPROP 0 LASTPIN (-7150 6250) $PN B19
J 2
(-7160 6260);
DISPLAY 0.680851 (-7160 6260);
PAINT MONO (-7160 6260);
FORCEPROP 0 LASTPIN (-7150 5850) $PN B23
J 2
(-7160 5860);
DISPLAY 0.680851 (-7160 5860);
PAINT MONO (-7160 5860);
FORCEPROP 0 LASTPIN (-7150 5450) $PN B27
J 2
(-7160 5460);
DISPLAY 0.680851 (-7160 5460);
PAINT MONO (-7160 5460);
FORCEPROP 0 LASTPIN (-5850 8150) $PN A1
J 0
(-5840 8160);
DISPLAY 0.680851 (-5840 8160);
PAINT MONO (-5840 8160);
FORCEPROP 0 LASTPIN (-7150 6450) $PN B17
J 2
(-7160 6460);
DISPLAY 0.680851 (-7160 6460);
PAINT MONO (-7160 6460);
FORCEPROP 0 LASTPIN (-7150 5050) $PN B31
J 2
(-7160 5060);
DISPLAY 0.680851 (-7160 5060);
PAINT MONO (-7160 5060);
FORCEPROP 0 LASTPIN (-5850 6750) $PN A14
J 0
(-5840 6760);
DISPLAY 0.680851 (-5840 6760);
PAINT MONO (-5840 6760);
FORCEPROP 0 LASTPIN (-5850 6850) $PN A13
J 0
(-5840 6860);
DISPLAY 0.680851 (-5840 6860);
PAINT MONO (-5840 6860);
FORCEPROP 0 LASTPIN (-7150 6950) $PN B12
J 2
(-7160 6960);
DISPLAY 0.680851 (-7160 6960);
PAINT MONO (-7160 6960);
FORCEPROP 0 LASTPIN (-5850 6250) $PN A19
J 0
(-5840 6260);
DISPLAY 0.680851 (-5840 6260);
PAINT MONO (-5840 6260);
FORCEPROP 0 LASTPIN (-7150 5150) $PN B30
J 2
(-7160 5160);
DISPLAY 0.680851 (-7160 5160);
PAINT MONO (-7160 5160);
FORCEPROP 0 LASTPIN (-5850 4950) $PN A32
J 0
(-5840 4960);
DISPLAY 0.680851 (-5840 4960);
PAINT MONO (-5840 4960);
FORCEPROP 0 LASTPIN (-7150 7750) $PN B5
J 2
(-7160 7760);
DISPLAY 0.680851 (-7160 7760);
PAINT MONO (-7160 7760);
FORCEPROP 0 LASTPIN (-7150 7650) $PN B6
J 2
(-7160 7660);
DISPLAY 0.680851 (-7160 7660);
PAINT MONO (-7160 7660);
FORCEPROP 0 LASTPIN (-7150 7150) $PN B11
J 2
(-7160 7160);
DISPLAY 0.680851 (-7160 7160);
PAINT MONO (-7160 7160);
FORCEPROP 1 LAST CLS_PN S_M_EF64_PCIE_P0394_V1
J 0
(-7100 8500);
DISPLAY 1.212766 (-7100 8500);
PAINT GREEN (-7100 8500);
FORCEPROP 0 LAST NO_ASSY TRUE
J 0
(-6850 8400);
DISPLAY 1.276596 (-6850 8400);
DISPLAY BOTH (-6850 8400);
FORCEPROP 1 LAST CDS_LMAN_SYM_OUTLINE 0,0,1100,-3500
J 0
(-7050 8350);
DISPLAY 0.468085 (-7050 8350);
PAINT GREEN (-7050 8350);
DISPLAY INVISIBLE (-7050 8350);
FORCEPROP 2 LAST CDS_LIB connector
J 0
(-7050 8350);
DISPLAY INVISIBLE (-7050 8350);
FORCEPROP 1 LAST PATH I61
J 0
(-7000 8400);
DISPLAY 1.212766 (-7000 8400);
PAINT GREEN (-7000 8400);
DISPLAY INVISIBLE (-7000 8400);
FORCEADD RESISTOR..2
(-1250 6700);
FORCEPROP 1 LAST $LOCATION R55
J 0
(-1200 6600);
DISPLAY 1.212766 (-1200 6600);
PAINT GREEN (-1200 6600);
FORCEPROP 0 LAST CDS_LOCATION R55
J 0
(-1200 6800);
DISPLAY 1.021277 (-1200 6800);
DISPLAY INVISIBLE (-1200 6800);
FORCEPROP 0 LAST $SEC 1
J 0
(-1200 6800);
DISPLAY 0.680851 (-1200 6800);
PAINT MONO (-1200 6800);
DISPLAY INVISIBLE (-1200 6800);
FORCEPROP 0 LAST CDS_SEC 1
J 0
(-1200 6800);
DISPLAY 1.021277 (-1200 6800);
DISPLAY INVISIBLE (-1200 6800);
FORCEPROP 0 LASTPIN (-1250 6800) $PN 1
R 1
J 0
(-1260 6810);
DISPLAY 0.680851 (-1260 6810);
PAINT MONO (-1260 6810);
FORCEPROP 0 LASTPIN (-1250 6550) $PN 2
R 1
J 2
(-1260 6540);
DISPLAY 0.680851 (-1260 6540);
PAINT MONO (-1260 6540);
FORCEPROP 1 LAST VALUE 4.7KOHM
J 0
(-1200 6700);
DISPLAY 0.978723 (-1200 6700);
PAINT GREEN (-1200 6700);
FORCEPROP 0 LAST PACKAGE 0402
J 0
(-1200 6800);
DISPLAY 1.021277 (-1200 6800);
FORCEPROP 0 LAST NO_ASSY TRUE
J 0
(-1200 6550);
DISPLAY 0.638298 (-1200 6550);
DISPLAY BOTH (-1200 6550);
FORCEPROP 2 LAST CDS_LIB passive
J 0
(-1250 6700);
DISPLAY INVISIBLE (-1250 6700);
FORCEPROP 1 LAST CDS_LMAN_SYM_OUTLINE -50,50,50,-100
J 0
(-1250 6700);
DISPLAY 0.468085 (-1250 6700);
PAINT GREEN (-1250 6700);
DISPLAY INVISIBLE (-1250 6700);
FORCEPROP 1 LAST CLS_PN G155-14701-01
J 0
(-1386 6900);
DISPLAY 1.212766 (-1386 6900);
PAINT GREEN (-1386 6900);
DISPLAY INVISIBLE (-1386 6900);
FORCEPROP 1 LAST TOLERANCE 1%
J 0
(-1447 6955);
DISPLAY 1.212766 (-1447 6955);
PAINT GREEN (-1447 6955);
DISPLAY INVISIBLE (-1447 6955);
FORCEPROP 1 LAST PATH I62
J 0
(-1447 6805);
DISPLAY 1.212766 (-1447 6805);
PAINT GREEN (-1447 6805);
DISPLAY INVISIBLE (-1447 6805);
FORCEADD RESISTOR..2
(-1300 7600);
FORCEPROP 1 LAST $LOCATION R56
J 0
(-1250 7500);
DISPLAY 1.212766 (-1250 7500);
PAINT GREEN (-1250 7500);
FORCEPROP 0 LAST CDS_LOCATION R56
J 0
(-1250 7700);
DISPLAY 1.021277 (-1250 7700);
DISPLAY INVISIBLE (-1250 7700);
FORCEPROP 0 LAST $SEC 1
J 0
(-1250 7700);
DISPLAY 0.680851 (-1250 7700);
PAINT MONO (-1250 7700);
DISPLAY INVISIBLE (-1250 7700);
FORCEPROP 0 LAST CDS_SEC 1
J 0
(-1250 7700);
DISPLAY 1.021277 (-1250 7700);
DISPLAY INVISIBLE (-1250 7700);
FORCEPROP 0 LASTPIN (-1300 7700) $PN 1
R 1
J 0
(-1310 7710);
DISPLAY 0.680851 (-1310 7710);
PAINT MONO (-1310 7710);
FORCEPROP 0 LASTPIN (-1300 7450) $PN 2
R 1
J 2
(-1310 7440);
DISPLAY 0.680851 (-1310 7440);
PAINT MONO (-1310 7440);
FORCEPROP 1 LAST VALUE 4.7KOHM
J 0
(-1250 7650);
DISPLAY 0.978723 (-1250 7650);
PAINT GREEN (-1250 7650);
FORCEPROP 0 LAST PACKAGE 0402
J 0
(-1250 7750);
DISPLAY 1.021277 (-1250 7750);
FORCEPROP 1 LAST CLS_PN G155-14701-01
J 0
(-1436 7800);
DISPLAY 1.212766 (-1436 7800);
PAINT GREEN (-1436 7800);
DISPLAY INVISIBLE (-1436 7800);
FORCEPROP 1 LAST CDS_LMAN_SYM_OUTLINE -50,50,50,-100
J 0
(-1300 7600);
DISPLAY 0.468085 (-1300 7600);
PAINT GREEN (-1300 7600);
DISPLAY INVISIBLE (-1300 7600);
FORCEPROP 2 LAST CDS_LIB passive
J 0
(-1300 7600);
DISPLAY INVISIBLE (-1300 7600);
FORCEPROP 1 LAST TOLERANCE 1%
J 0
(-1497 7855);
DISPLAY 1.212766 (-1497 7855);
PAINT GREEN (-1497 7855);
DISPLAY INVISIBLE (-1497 7855);
FORCEPROP 1 LAST PATH I63
J 0
(-1497 7705);
DISPLAY 1.212766 (-1497 7705);
PAINT GREEN (-1497 7705);
DISPLAY INVISIBLE (-1497 7705);
FORCEADD OFFPAGE_OUT..1
R 2
(-9650 5450);
FORCEPROP 2 LAST $XR0 10D5< 
J 0
(-9833 5450);
DISPLAY 0.638298 (-9833 5450);
PAINT MONO (-9833 5450);
FORCEPROP 1 LAST BODY_TYPE COMMENT
J 2
(-9660 5585);
DISPLAY 0.808511 (-9660 5585);
PAINT GREEN (-9660 5585);
DISPLAY INVISIBLE (-9660 5585);
FORCEPROP 1 LAST CDS_LMAN_SYM_OUTLINE -50,50,50,-50
J 2
(-9650 5450);
DISPLAY 0.468085 (-9650 5450);
PAINT GREEN (-9650 5450);
DISPLAY INVISIBLE (-9650 5450);
FORCEPROP 2 LAST CDS_LIB cls
J 0
(-9650 5450);
DISPLAY INVISIBLE (-9650 5450);
FORCEPROP 1 LAST OFFPAGE TRUE
J 2
(-9660 5505);
DISPLAY 0.808511 (-9660 5505);
PAINT GREEN (-9660 5505);
DISPLAY INVISIBLE (-9660 5505);
FORCEPROP 2 LAST PATH I7
J 0
(-9800 5500);
DISPLAY 1.021277 (-9800 5500);
DISPLAY INVISIBLE (-9800 5500);
FORCEADD OFFPAGE_OUT..1
R 2
(-9650 5750);
FORCEPROP 2 LAST $XR0 10C5< 
J 0
(-9833 5750);
DISPLAY 0.638298 (-9833 5750);
PAINT MONO (-9833 5750);
FORCEPROP 1 LAST BODY_TYPE COMMENT
J 2
(-9660 5885);
DISPLAY 0.808511 (-9660 5885);
PAINT GREEN (-9660 5885);
DISPLAY INVISIBLE (-9660 5885);
FORCEPROP 1 LAST CDS_LMAN_SYM_OUTLINE -50,50,50,-50
J 2
(-9650 5750);
DISPLAY 0.468085 (-9650 5750);
PAINT GREEN (-9650 5750);
DISPLAY INVISIBLE (-9650 5750);
FORCEPROP 2 LAST CDS_LIB cls
J 0
(-9650 5750);
DISPLAY INVISIBLE (-9650 5750);
FORCEPROP 1 LAST OFFPAGE TRUE
J 2
(-9660 5805);
DISPLAY 0.808511 (-9660 5805);
PAINT GREEN (-9660 5805);
DISPLAY INVISIBLE (-9660 5805);
FORCEPROP 2 LAST PATH I8
J 0
(-9800 5800);
DISPLAY 1.021277 (-9800 5800);
DISPLAY INVISIBLE (-9800 5800);
FORCEADD OFFPAGE_BI..1
R 2
(-9650 7750);
FORCEPROP 2 LAST $XR0 9K3< 
J 0
(-9807 7750);
DISPLAY 0.638298 (-9807 7750);
PAINT MONO (-9807 7750);
FORCEPROP 2 LAST CDS_LIB cls
J 0
(-9650 7750);
DISPLAY INVISIBLE (-9650 7750);
FORCEPROP 1 LAST CDS_LMAN_SYM_OUTLINE -50,50,50,-50
J 2
(-9650 7750);
DISPLAY 0.468085 (-9650 7750);
PAINT GREEN (-9650 7750);
DISPLAY INVISIBLE (-9650 7750);
FORCEPROP 1 LAST BODY_TYPE COMMENT
J 2
(-9660 7885);
DISPLAY 0.808511 (-9660 7885);
PAINT GREEN (-9660 7885);
DISPLAY INVISIBLE (-9660 7885);
FORCEPROP 1 LAST OFFPAGE TRUE
J 2
(-9660 7805);
DISPLAY 0.808511 (-9660 7805);
PAINT GREEN (-9660 7805);
DISPLAY INVISIBLE (-9660 7805);
FORCEPROP 2 LAST PATH I81
J 0
(-9600 7850);
DISPLAY 1.021277 (-9600 7850);
DISPLAY INVISIBLE (-9600 7850);
FORCEADD OFFPAGE_BI..1
R 2
(-9650 7650);
FORCEPROP 2 LAST $XR0 9K3<> 
J 0
(-9838 7650);
DISPLAY 0.638298 (-9838 7650);
PAINT MONO (-9838 7650);
FORCEPROP 2 LAST CDS_LIB cls
J 0
(-9650 7650);
DISPLAY INVISIBLE (-9650 7650);
FORCEPROP 1 LAST CDS_LMAN_SYM_OUTLINE -50,50,50,-50
J 2
(-9650 7650);
DISPLAY 0.468085 (-9650 7650);
PAINT GREEN (-9650 7650);
DISPLAY INVISIBLE (-9650 7650);
FORCEPROP 1 LAST BODY_TYPE COMMENT
J 2
(-9660 7785);
DISPLAY 0.808511 (-9660 7785);
PAINT GREEN (-9660 7785);
DISPLAY INVISIBLE (-9660 7785);
FORCEPROP 1 LAST OFFPAGE TRUE
J 2
(-9660 7705);
DISPLAY 0.808511 (-9660 7705);
PAINT GREEN (-9660 7705);
DISPLAY INVISIBLE (-9660 7705);
FORCEPROP 2 LAST PATH I82
J 0
(-9600 7750);
DISPLAY 1.021277 (-9600 7750);
DISPLAY INVISIBLE (-9600 7750);
FORCEADD OFFPAGE_BI..2
(-9550 1900);
FORCEPROP 2 LAST $XR0 9D3<> 
J 0
(-9738 1900);
DISPLAY 0.638298 (-9738 1900);
PAINT MONO (-9738 1900);
FORCEPROP 2 LAST PATH I86
J 0
(-9500 2000);
DISPLAY 1.021277 (-9500 2000);
DISPLAY INVISIBLE (-9500 2000);
FORCEPROP 1 LAST OFFPAGE TRUE
J 0
(-9540 1955);
DISPLAY 0.808511 (-9540 1955);
PAINT GREEN (-9540 1955);
DISPLAY INVISIBLE (-9540 1955);
FORCEPROP 1 LAST CDS_LMAN_SYM_OUTLINE -50,50,50,-50
J 0
(-9550 1900);
DISPLAY 0.468085 (-9550 1900);
PAINT GREEN (-9550 1900);
DISPLAY INVISIBLE (-9550 1900);
FORCEPROP 2 LAST CDS_LIB cls
J 0
(-9550 1900);
DISPLAY INVISIBLE (-9550 1900);
FORCEPROP 1 LAST BODY_TYPE COMMENT
J 0
(-9540 2035);
DISPLAY 0.808511 (-9540 2035);
PAINT GREEN (-9540 2035);
DISPLAY INVISIBLE (-9540 2035);
FORCEADD OFFPAGE_IN..1
(-9550 1800);
FORCEPROP 2 LAST $XR0 9D3<> 
J 0
(-9733 1800);
DISPLAY 0.638298 (-9733 1800);
PAINT MONO (-9733 1800);
FORCEPROP 2 LAST PATH I87
J 0
(-9500 1900);
DISPLAY 1.021277 (-9500 1900);
DISPLAY INVISIBLE (-9500 1900);
FORCEPROP 1 LAST OFFPAGE TRUE
J 0
(-9540 1855);
DISPLAY 0.808511 (-9540 1855);
PAINT GREEN (-9540 1855);
DISPLAY INVISIBLE (-9540 1855);
FORCEPROP 2 LAST CDS_LIB cls
J 0
(-9550 1800);
DISPLAY INVISIBLE (-9550 1800);
FORCEPROP 1 LAST CDS_LMAN_SYM_OUTLINE -50,50,50,-50
J 0
(-9550 1800);
DISPLAY 0.468085 (-9550 1800);
PAINT GREEN (-9550 1800);
DISPLAY INVISIBLE (-9550 1800);
FORCEPROP 1 LAST BODY_TYPE COMMENT
J 0
(-9540 1935);
DISPLAY 0.808511 (-9540 1935);
PAINT GREEN (-9540 1935);
DISPLAY INVISIBLE (-9540 1935);
FORCEADD OFFPAGE_OUT..1
R 2
(-9650 5850);
FORCEPROP 2 LAST $XR0 10C5< 
J 0
(-9833 5850);
DISPLAY 0.638298 (-9833 5850);
PAINT MONO (-9833 5850);
FORCEPROP 2 LAST CDS_LIB cls
J 0
(-9650 5850);
DISPLAY INVISIBLE (-9650 5850);
FORCEPROP 1 LAST CDS_LMAN_SYM_OUTLINE -50,50,50,-50
J 2
(-9650 5850);
DISPLAY 0.468085 (-9650 5850);
PAINT GREEN (-9650 5850);
DISPLAY INVISIBLE (-9650 5850);
FORCEPROP 1 LAST BODY_TYPE COMMENT
J 2
(-9660 5985);
DISPLAY 0.808511 (-9660 5985);
PAINT GREEN (-9660 5985);
DISPLAY INVISIBLE (-9660 5985);
FORCEPROP 1 LAST OFFPAGE TRUE
J 2
(-9660 5905);
DISPLAY 0.808511 (-9660 5905);
PAINT GREEN (-9660 5905);
DISPLAY INVISIBLE (-9660 5905);
FORCEPROP 2 LAST PATH I9
J 0
(-9800 5900);
DISPLAY 1.021277 (-9800 5900);
DISPLAY INVISIBLE (-9800 5900);
FORCEADD GND_SG..1
(-7950 2400);
FORCEPROP 3 LASTPIN (-7900 2450) SIG_NAME SG\g
J 0
(-7890 2460);
DISPLAY 0.659574 (-7890 2460);
PAINT MONO (-7890 2460);
DISPLAY INVISIBLE (-7890 2460);
FORCEPROP 1 LAST HDL_POWER SG
J 1
(-7895 2305);
DISPLAY 0.808511 (-7895 2305);
PAINT GREEN (-7895 2305);
FORCEPROP 1 LAST PATH I91
J 0
(-7915 2400);
DISPLAY 0.808511 (-7915 2400);
PAINT GREEN (-7915 2400);
DISPLAY INVISIBLE (-7915 2400);
FORCEPROP 1 LAST BODY_TYPE PLUMBING
J 0
(-7935 2385);
DISPLAY 0.808511 (-7935 2385);
PAINT GREEN (-7935 2385);
DISPLAY INVISIBLE (-7935 2385);
FORCEPROP 2 LAST CDS_LIB cls
J 0
(-7950 2400);
DISPLAY INVISIBLE (-7950 2400);
FORCEPROP 1 LAST CDS_LMAN_SYM_OUTLINE 0,0,100,-50
J 0
(-7950 2400);
DISPLAY 0.468085 (-7950 2400);
PAINT GREEN (-7950 2400);
DISPLAY INVISIBLE (-7950 2400);
FORCEPROP 0 LAST VOLTAGE 0
J 0
(-7850 2400);
DISPLAY 1.021277 (-7850 2400);
DISPLAY INVISIBLE (-7850 2400);
FORCEADD CAPACITOR..2
(-7900 2700);
FORCEPROP 1 LAST $LOCATION C17
J 0
(-7850 2550);
DISPLAY 1.212766 (-7850 2550);
PAINT GREEN (-7850 2550);
FORCEPROP 0 LAST CDS_LOCATION C17
J 0
(-7850 2850);
DISPLAY 1.021277 (-7850 2850);
DISPLAY INVISIBLE (-7850 2850);
FORCEPROP 0 LAST $SEC 1
J 0
(-7850 2850);
DISPLAY 0.680851 (-7850 2850);
PAINT MONO (-7850 2850);
DISPLAY INVISIBLE (-7850 2850);
FORCEPROP 0 LAST CDS_SEC 1
J 0
(-7850 2850);
DISPLAY 1.021277 (-7850 2850);
DISPLAY INVISIBLE (-7850 2850);
FORCEPROP 0 LASTPIN (-7900 2800) $PN 1
R 1
J 0
(-7910 2810);
DISPLAY 0.680851 (-7910 2810);
PAINT MONO (-7910 2810);
FORCEPROP 0 LASTPIN (-7900 2550) $PN 2
R 1
J 2
(-7910 2540);
DISPLAY 0.680851 (-7910 2540);
PAINT MONO (-7910 2540);
FORCEPROP 0 LAST PACKAGE 0402
J 0
(-7750 2650);
DISPLAY 0.808511 (-7750 2650);
FORCEPROP 0 LAST NO_ASSY TRUE
J 0
(-7850 2700);
DISPLAY 0.638298 (-7850 2700);
DISPLAY BOTH (-7850 2700);
FORCEPROP 1 LAST VALUE 0.1UF
J 0
(-7850 2750);
DISPLAY 1.212766 (-7850 2750);
PAINT GREEN (-7850 2750);
FORCEPROP 1 LAST PATH I92
J 0
(-8000 2750);
DISPLAY 1.212766 (-8000 2750);
PAINT GREEN (-8000 2750);
DISPLAY INVISIBLE (-8000 2750);
FORCEPROP 1 LAST TOLERANCE 10%
J 0
(-8050 2800);
DISPLAY 1.212766 (-8050 2800);
PAINT GREEN (-8050 2800);
DISPLAY INVISIBLE (-8050 2800);
FORCEPROP 1 LAST CLS_PN G105-0B104-CK
J 0
(-8000 2750);
DISPLAY 1.212766 (-8000 2750);
PAINT GREEN (-8000 2750);
DISPLAY INVISIBLE (-8000 2750);
FORCEPROP 1 LAST CDS_LMAN_SYM_OUTLINE -50,0,50,-50
J 0
(-7900 2700);
DISPLAY 0.468085 (-7900 2700);
PAINT GREEN (-7900 2700);
DISPLAY INVISIBLE (-7900 2700);
FORCEPROP 2 LAST CDS_LIB passive
J 0
(-7900 2700);
DISPLAY INVISIBLE (-7900 2700);
FORCEADD GND_SG..1
(-5750 1600);
FORCEPROP 3 LASTPIN (-5700 1650) SIG_NAME SG\g
J 0
(-5690 1660);
DISPLAY 0.659574 (-5690 1660);
PAINT MONO (-5690 1660);
DISPLAY INVISIBLE (-5690 1660);
FORCEPROP 1 LAST HDL_POWER SG
J 1
(-5695 1505);
DISPLAY 0.808511 (-5695 1505);
PAINT GREEN (-5695 1505);
FORCEPROP 1 LAST PATH I94
J 0
(-5715 1600);
DISPLAY 0.808511 (-5715 1600);
PAINT GREEN (-5715 1600);
DISPLAY INVISIBLE (-5715 1600);
FORCEPROP 1 LAST BODY_TYPE PLUMBING
J 0
(-5735 1585);
DISPLAY 0.808511 (-5735 1585);
PAINT GREEN (-5735 1585);
DISPLAY INVISIBLE (-5735 1585);
FORCEPROP 1 LAST CDS_LMAN_SYM_OUTLINE 0,0,100,-50
J 0
(-5750 1600);
DISPLAY 0.468085 (-5750 1600);
PAINT GREEN (-5750 1600);
DISPLAY INVISIBLE (-5750 1600);
FORCEPROP 2 LAST CDS_LIB cls
J 0
(-5750 1600);
DISPLAY INVISIBLE (-5750 1600);
FORCEADD SHEET_A1..1
(3550 -150);
FORCEPROP 2 LAST CUSTOM_TXT_CDS <XR_PAGE_TITLE>
J 0
(-12020 11200);
DISPLAY 0.638298 (-12020 11200);
PAINT PINK (-12020 11200);
FORCEPROP 1 LAST CUSTOM_TXT_CDS <DOCNO>
J 0
(1500 235);
DISPLAY 0.978723 (1500 235);
FORCEPROP 1 LAST CUSTOM_TXT_CDS <CON_PAGE_NUM>
J 0
(1395 -100);
DISPLAY 0.978723 (1395 -100);
FORCEPROP 1 LAST CUSTOM_TXT_CDS <DATE>
J 0
(2850 25);
DISPLAY 0.978723 (2850 25);
FORCEPROP 1 LAST CUSTOM_TXT_CDS <TITLE>
J 1
(1765 480);
DISPLAY 0.978723 (1765 480);
FORCEPROP 1 LAST CUSTOM_TXT_CDS <DESIGNER>
J 0
(2850 450);
DISPLAY 0.978723 (2850 450);
FORCEPROP 1 LAST CUSTOM_TXT_CDS <CON_TOTAL_PAGES>
J 0
(1705 -100);
DISPLAY 0.808511 (1705 -100);
FORCEPROP 1 LAST CUSTOM_TXT_CDS <ASSY_PN>
J 0
(1500 25);
DISPLAY 0.978723 (1500 25);
FORCEPROP 1 LAST CUSTOM_TXT_CDS <DOCREV>
J 0
(2850 225);
DISPLAY 0.978723 (2850 225);
FORCEPROP 1 LAST TITLE PCIEx4_GF_CONN
J 0
(1050 700);
DISPLAY 3.042553 (1050 700);
PAINT GREEN (1050 700);
FORCEPROP 2 LAST CDS_XR_PAGE_TITLE CR-9 : @TIMECARD_LIB.TIMECARD(SCH_1):PAGE9
J 0
(-12020 11200);
DISPLAY 0.638298 (-12020 11200);
PAINT PINK (-12020 11200);
DISPLAY INVISIBLE (-12020 11200);
FORCEPROP 2 LAST PAGE_BORDER TRUE
J 0
(-12020 11200);
DISPLAY 0.638298 (-12020 11200);
PAINT PINK (-12020 11200);
DISPLAY INVISIBLE (-12020 11200);
FORCEPROP 1 LAST CDS_LMAN_SYM_OUTLINE -15850,11500,200,-200
J 0
(3550 -150);
DISPLAY 0.468085 (3550 -150);
PAINT GREEN (3550 -150);
DISPLAY INVISIBLE (3550 -150);
FORCEPROP 2 LAST CDS_LIB cls
J 0
(3550 -150);
DISPLAY INVISIBLE (3550 -150);
FORCEPROP 1 LAST COMMENT_BODY TRUE
J 0
(3560 -95);
DISPLAY 0.808511 (3560 -95);
DISPLAY INVISIBLE (3560 -95);
WIRE 16 -1 (-4450 4100)(-4450 4250);
WIRE 16 -1 (-4450 4100)(-4850 4100);
WIRE 16 -1 (-1250 6550)(-1250 6400);
WIRE 16 -1 (-1300 7850)(-1300 7700);
WIRE 16 -1 (-7950 7450)(-7950 8800);
WIRE 16 -1 (-7150 7450)(-7950 7450);
WIRE 16 -1 (-7900 2550)(-7900 2450);
WIRE 16 -1 (-5700 1800)(-5700 1650);
WIRE 16 -1 (-5900 1800)(-5700 1800);
WIRE 16 -1 (1050 7000)(2250 7000);
FORCEPROP 2 LAST SIG_NAME PCIE_PERST_N
J 0
(1540 7010);
DISPLAY 1.021277 (1540 7010);
WIRE 16 -1 (-3850 5950)(-2050 5950);
FORCEPROP 2 LAST SIG_NAME CPU_RX_PCIE_MGT1_TXN
J 0
(-3010 5960);
DISPLAY 1.021277 (-3010 5960);
WIRE 16 -1 (-5850 5150)(-4100 5150);
FORCEPROP 2 LAST SIG_NAME C_CPU_RX_PCIE_MGT3_TXN
J 0
(-5560 5160);
DISPLAY 1.021277 (-5560 5160);
WIRE 16 -1 (-3850 5550)(-2050 5550);
FORCEPROP 2 LAST SIG_NAME CPU_RX_PCIE_MGT2_TXN
J 0
(-3010 5560);
DISPLAY 1.021277 (-3010 5560);
WIRE 16 -1 (-3800 7750)(-2550 7750);
FORCEPROP 2 LAST SIG_NAME FPGA_TCK
J 0
(-3110 7760);
DISPLAY 1.021277 (-3110 7760);
WIRE 16 -1 (-3800 7650)(-2550 7650);
FORCEPROP 2 LAST SIG_NAME FPGA_TDI
J 0
(-3110 7660);
DISPLAY 1.021277 (-3110 7660);
WIRE 16 -1 (-9600 7650)(-7150 7650);
FORCEPROP 2 LAST SIG_NAME PCIE_CONN_SMDAT
J 0
(-9510 7660);
DISPLAY 1.021277 (-9510 7660);
WIRE 16 -1 (-7150 6450)(-8250 6450);
WIRE 16 -1 (-5850 6850)(-4100 6850);
FORCEPROP 2 LAST SIG_NAME C_PCIEREFCLKP
J 0
(-5560 6860);
DISPLAY 1.021277 (-5560 6860);
WIRE 16 -1 (-5850 6550)(-4100 6550);
FORCEPROP 2 LAST SIG_NAME C_CPU_RX_PCIE_MGT0_TXP
J 0
(-5560 6560);
DISPLAY 1.021277 (-5560 6560);
WIRE 16 -1 (-5850 6050)(-4100 6050);
FORCEPROP 2 LAST SIG_NAME C_CPU_RX_PCIE_MGT1_TXP
J 0
(-5560 6060);
DISPLAY 1.021277 (-5560 6060);
WIRE 16 -1 (-5850 7650)(-4050 7650);
FORCEPROP 2 LAST SIG_NAME PCIE_CONN_TDI
J 0
(-5260 7660);
DISPLAY 1.021277 (-5260 7660);
WIRE 16 -1 (-5850 7550)(-4050 7550);
FORCEPROP 2 LAST SIG_NAME PCIE_CONN_TDO
J 0
(-5260 7560);
DISPLAY 1.021277 (-5260 7560);
WIRE 16 -1 (-3800 7450)(-2550 7450);
FORCEPROP 2 LAST SIG_NAME FPGA_TMS
J 0
(-3110 7460);
DISPLAY 1.021277 (-3110 7460);
WIRE 16 -1 (-5850 8150)(-4450 8150);
FORCEPROP 2 LAST SIG_NAME CARD_PRESENT
J 0
(-5210 8160);
DISPLAY 1.021277 (-5210 8160);
WIRE 16 -1 (-5850 5650)(-4100 5650);
FORCEPROP 2 LAST SIG_NAME C_CPU_RX_PCIE_MGT2_TXP
J 0
(-5560 5660);
DISPLAY 1.021277 (-5560 5660);
WIRE 16 -1 (-5850 5550)(-4100 5550);
FORCEPROP 2 LAST SIG_NAME C_CPU_RX_PCIE_MGT2_TXN
J 0
(-5560 5560);
DISPLAY 1.021277 (-5560 5560);
WIRE 16 -1 (-3850 6550)(-2050 6550);
FORCEPROP 2 LAST SIG_NAME CPU_RX_PCIE_MGT0_TXP
J 0
(-3010 6560);
DISPLAY 1.021277 (-3010 6560);
WIRE 16 -1 (-3850 6450)(-2050 6450);
FORCEPROP 2 LAST SIG_NAME CPU_RX_PCIE_MGT0_TXN
J 0
(-3010 6460);
DISPLAY 1.021277 (-3010 6460);
WIRE 16 -1 (-2050 6850)(-3850 6850);
FORCEPROP 2 LAST SIG_NAME PCIE_REFCLKP
J 0
(-2660 6860);
DISPLAY 1.021277 (-2660 6860);
WIRE 16 -1 (-2050 6750)(-3850 6750);
FORCEPROP 2 LAST SIG_NAME PCIE_REFCLKN
J 0
(-2660 6760);
DISPLAY 1.021277 (-2660 6760);
WIRE 16 -1 (-5850 5950)(-4100 5950);
FORCEPROP 2 LAST SIG_NAME C_CPU_RX_PCIE_MGT1_TXN
J 0
(-5560 5960);
DISPLAY 1.021277 (-5560 5960);
WIRE 16 -1 (-5850 6450)(-4100 6450);
FORCEPROP 2 LAST SIG_NAME C_CPU_RX_PCIE_MGT0_TXN
J 0
(-5560 6460);
DISPLAY 1.021277 (-5560 6460);
WIRE 16 -1 (-9500 2100)(-8000 2100);
FORCEPROP 2 LAST SIG_NAME FPGA_OUT_I2C_BUFFER_EN
J 0
(-9460 2110);
DISPLAY 1.021277 (-9460 2110);
WIRE 16 -1 (-7350 2450)(-7350 2100);
WIRE 16 -1 (-6800 2100)(-7350 2100);
WIRE 16 -1 (-7750 2100)(-7350 2100);
WIRE 16 -1 (-8100 5050)(-7150 5050);
WIRE 16 -1 (-7150 6750)(-9600 6750);
FORCEPROP 2 LAST SIG_NAME CPU_TX_PCIE_MGT_0_RXP
J 0
(-9510 6760);
DISPLAY 1.021277 (-9510 6760);
WIRE 16 -1 (-7150 6150)(-9600 6150);
FORCEPROP 2 LAST SIG_NAME CPU_TX_PCIE_MGT_1_RXN
J 0
(-9510 6160);
DISPLAY 1.021277 (-9510 6160);
WIRE 16 -1 (-7150 5850)(-9600 5850);
FORCEPROP 2 LAST SIG_NAME CPU_TX_PCIE_MGT_2_RXP
J 0
(-9510 5860);
DISPLAY 1.021277 (-9510 5860);
WIRE 16 -1 (-7150 5350)(-9600 5350);
FORCEPROP 2 LAST SIG_NAME CPU_TX_PCIE_MGT_3_RXN
J 0
(-9510 5360);
DISPLAY 1.021277 (-9510 5360);
WIRE 16 -1 (-7150 5450)(-9600 5450);
FORCEPROP 2 LAST SIG_NAME CPU_TX_PCIE_MGT_3_RXP
J 0
(-9510 5460);
DISPLAY 1.021277 (-9510 5460);
WIRE 16 -1 (-5850 6750)(-4100 6750);
FORCEPROP 2 LAST SIG_NAME C_PCIEREFCLKN
J 0
(-5560 6760);
DISPLAY 1.021277 (-5560 6760);
WIRE 16 -1 (-3850 6050)(-2050 6050);
FORCEPROP 2 LAST SIG_NAME CPU_RX_PCIE_MGT1_TXP
J 0
(-3010 6060);
DISPLAY 1.021277 (-3010 6060);
WIRE 16 -1 (-3850 5250)(-2050 5250);
FORCEPROP 2 LAST SIG_NAME CPU_RX_PCIE_MGT3_TXP
J 0
(-3010 5260);
DISPLAY 1.021277 (-3010 5260);
WIRE 16 -1 (-5850 7750)(-4050 7750);
FORCEPROP 2 LAST SIG_NAME PCIE_CONN_TCK
J 0
(-5260 7760);
DISPLAY 1.021277 (-5260 7760);
WIRE 16 -1 (-3800 7550)(-2550 7550);
FORCEPROP 2 LAST SIG_NAME FPGA_TDO
J 0
(-3110 7560);
DISPLAY 1.021277 (-3110 7560);
WIRE 16 -1 (-3850 2200)(-5900 2200);
FORCEPROP 2 LAST SIG_NAME PCIE_SMCLK
J 0
(-4460 2210);
DISPLAY 1.021277 (-4460 2210);
WIRE 16 -1 (-7150 6250)(-9600 6250);
FORCEPROP 2 LAST SIG_NAME CPU_TX_PCIE_MGT_1_RXP
J 0
(-9510 6260);
DISPLAY 1.021277 (-9510 6260);
WIRE 16 -1 (-7150 5750)(-9600 5750);
FORCEPROP 2 LAST SIG_NAME CPU_TX_PCIE_MGT_2_RXN
J 0
(-9510 5760);
DISPLAY 1.021277 (-9510 5760);
WIRE 16 -1 (-5850 5250)(-4100 5250);
FORCEPROP 2 LAST SIG_NAME C_CPU_RX_PCIE_MGT3_TXP
J 0
(-5560 5260);
DISPLAY 1.021277 (-5560 5260);
WIRE 16 -1 (-3850 5650)(-2050 5650);
FORCEPROP 2 LAST SIG_NAME CPU_RX_PCIE_MGT2_TXP
J 0
(-3010 5660);
DISPLAY 1.021277 (-3010 5660);
WIRE 16 -1 (-1400 7050)(-1250 7050);
WIRE 16 -1 (-1250 7150)(-1250 7050);
WIRE 16 -1 (-1250 6800)(-1250 7050);
WIRE 16 -1 (-1000 7150)(-1250 7150);
WIRE 16 -1 (-1250 7150)(-1300 7150);
WIRE 16 -1 (-1300 7450)(-1300 7150);
WIRE 16 -1 (-5850 7150)(-1300 7150);
FORCEPROP 2 LAST SIG_NAME PCIE_CONN_PERST_N
J 0
(-5260 7160);
DISPLAY 1.021277 (-5260 7160);
WIRE 16 -1 (-5850 7450)(-4050 7450);
FORCEPROP 2 LAST SIG_NAME PCIE_CONN_TMS
J 0
(-5260 7460);
DISPLAY 1.021277 (-5260 7460);
WIRE 16 -1 (-9500 1900)(-6800 1900);
FORCEPROP 2 LAST SIG_NAME PCIE_CONN_SMDAT
J 0
(-9410 1910);
DISPLAY 1.021277 (-9410 1910);
WIRE 16 -1 (-9500 1800)(-6800 1800);
FORCEPROP 2 LAST SIG_NAME PCIE_CONN_SMCLK
J 0
(-9410 1810);
DISPLAY 1.021277 (-9410 1810);
WIRE 16 -1 (-7150 6650)(-9600 6650);
FORCEPROP 2 LAST SIG_NAME CPU_TX_PCIE_MGT_0_RXN
J 0
(-9510 6660);
DISPLAY 1.021277 (-9510 6660);
WIRE 16 -1 (450 3450)(350 3450);
WIRE 16 -1 (450 3500)(450 3450);
WIRE 16 -1 (450 3500)(650 3500);
WIRE 16 -1 (450 3850)(450 3500);
WIRE 16 -1 (650 3500)(650 3450);
WIRE 16 -1 (-3850 5150)(-2050 5150);
FORCEPROP 2 LAST SIG_NAME CPU_RX_PCIE_MGT3_TXN
J 0
(-3010 5160);
DISPLAY 1.021277 (-3010 5160);
WIRE 16 -1 (-8500 6450)(-9600 6450);
FORCEPROP 2 LAST SIG_NAME CARD_PRESENT
J 0
(-9510 6460);
DISPLAY 1.021277 (-9510 6460);
WIRE 16 -1 (1050 7150)(2250 7150);
FORCEPROP 2 LAST SIG_NAME FPGA_PROGRAM_N
J 0
(1540 7160);
DISPLAY 1.021277 (1540 7160);
WIRE 16 -1 (800 7000)(450 7000);
WIRE 16 -1 (450 7150)(450 7000);
WIRE 16 -1 (800 7150)(450 7150);
WIRE 16 -1 (-450 7150)(450 7150);
FORCEPROP 2 LAST SIG_NAME BF_PCIE_PERST_N
J 0
(-360 7160);
DISPLAY 1.021277 (-360 7160);
WIRE 16 -1 (-8350 5050)(-9600 5050);
FORCEPROP 2 LAST SIG_NAME CARD_PRESENT
J 0
(-9510 5060);
DISPLAY 1.021277 (-9510 5060);
WIRE 16 -1 (-9600 7750)(-7150 7750);
FORCEPROP 2 LAST SIG_NAME PCIE_CONN_SMCLK
J 0
(-9510 7760);
DISPLAY 1.021277 (-9510 7760);
WIRE 16 -1 (-700 5300)(-700 5350);
WIRE 16 -1 (-250 5350)(-700 5350);
WIRE 16 -1 (-700 5350)(-700 5400);
WIRE 16 -1 (-250 5350)(-250 5650);
WIRE 16 -1 (-250 5900)(-250 6150);
WIRE 16 -1 (-250 6150)(-700 6150);
WIRE 16 -1 (-700 6150)(-700 6200);
WIRE 16 -1 (-700 6100)(-700 6150);
WIRE 16 -1 (-5500 3750)(-5500 3650);
WIRE 16 -1 (-5900 3650)(-5500 3650);
WIRE 16 -1 (-5900 3550)(-5900 3650);
WIRE 16 -1 (-5900 3750)(-5900 3650);
WIRE 16 -1 (-6650 3750)(-6650 3650);
WIRE 16 -1 (-7050 3650)(-6650 3650);
WIRE 16 -1 (-7050 3550)(-7050 3650);
WIRE 16 -1 (-7050 3750)(-7050 3650);
WIRE 16 -1 (-5900 4100)(-5500 4100);
WIRE 16 -1 (-5900 4100)(-5900 4200);
WIRE 16 -1 (-5900 4000)(-5900 4100);
WIRE 16 -1 (-5500 4100)(-5250 4100);
WIRE 16 -1 (-5500 4000)(-5500 4100);
WIRE 16 -1 (-7050 4100)(-6650 4100);
WIRE 16 -1 (-7050 4100)(-7050 4150);
WIRE 16 -1 (-7050 4000)(-7050 4100);
WIRE 16 -1 (-6650 4000)(-6650 4100);
WIRE 16 -1 (-700 3650)(-700 3450);
WIRE 16 -1 (-700 3650)(-700 3950);
WIRE 16 -1 (-700 3650)(-550 3650);
WIRE 16 -1 (-700 3450)(-550 3450);
WIRE 16 -1 (-700 3950)(-1350 3950);
WIRE 16 -1 (-700 3950)(-700 4050);
WIRE 16 -1 (-1350 3950)(-1350 3750);
WIRE 16 -1 (850 4250)(850 4300);
WIRE 16 -1 (850 4100)(850 4250);
WIRE 16 -1 (450 4250)(850 4250);
WIRE 16 -1 (450 4100)(450 4250);
WIRE 16 -1 (-7150 7850)(-7300 7850);
WIRE 16 -1 (-7300 7850)(-7300 7550);
WIRE 16 -1 (-7150 7550)(-7300 7550);
WIRE 16 -1 (-7300 7550)(-7300 6850);
WIRE 16 -1 (-7150 6850)(-7300 6850);
WIRE 16 -1 (-7300 6850)(-7300 6550);
WIRE 16 -1 (-7150 6550)(-7300 6550);
WIRE 16 -1 (-7300 6550)(-7300 6350);
WIRE 16 -1 (-7150 6350)(-7300 6350);
WIRE 16 -1 (-7300 6350)(-7300 6050);
WIRE 16 -1 (-7150 6050)(-7300 6050);
WIRE 16 -1 (-7300 6050)(-7300 5950);
WIRE 16 -1 (-7150 5950)(-7300 5950);
WIRE 16 -1 (-7300 5950)(-7300 5650);
WIRE 16 -1 (-7150 5650)(-7300 5650);
WIRE 16 -1 (-7300 5650)(-7300 5550);
WIRE 16 -1 (-7150 5550)(-7300 5550);
WIRE 16 -1 (-7300 5550)(-7300 5250);
WIRE 16 -1 (-7150 5250)(-7300 5250);
WIRE 16 -1 (-7300 5250)(-7300 4950);
WIRE 16 -1 (-7150 4950)(-7300 4950);
WIRE 16 -1 (-7300 4950)(-7300 4800);
WIRE 16 -1 (-8650 8800)(-8650 7250);
WIRE 16 -1 (-8650 7250)(-7150 7250);
WIRE 16 -1 (-7350 7950)(-7150 7950);
WIRE 16 -1 (-7350 8050)(-7350 7950);
WIRE 16 -1 (-7350 8050)(-7150 8050);
WIRE 16 -1 (-7350 8150)(-7350 8050);
WIRE 16 -1 (-7350 8650)(-7350 8150);
WIRE 16 -1 (-7150 8150)(-7350 8150);
WIRE 16 -1 (-7350 8650)(-5650 8650);
WIRE 16 -1 (-7350 8800)(-7350 8650);
WIRE 16 -1 (-5650 8650)(-5650 8050);
WIRE 16 -1 (-5650 8050)(-5650 7950);
WIRE 16 -1 (-5850 8050)(-5650 8050);
WIRE 16 -1 (-5650 7950)(-5850 7950);
WIRE 16 -1 (-5850 7850)(-5700 7850);
WIRE 16 -1 (-5700 7850)(-5700 6950);
WIRE 16 -1 (-5850 6950)(-5700 6950);
WIRE 16 -1 (-5700 6950)(-5700 6650);
WIRE 16 -1 (-5850 6650)(-5700 6650);
WIRE 16 -1 (-5700 6650)(-5700 6350);
WIRE 16 -1 (-5850 6350)(-5700 6350);
WIRE 16 -1 (-5700 6350)(-5700 6150);
WIRE 16 -1 (-5850 6150)(-5700 6150);
WIRE 16 -1 (-5700 6150)(-5700 5850);
WIRE 16 -1 (-5850 5850)(-5700 5850);
WIRE 16 -1 (-5700 5850)(-5700 5750);
WIRE 16 -1 (-5850 5750)(-5700 5750);
WIRE 16 -1 (-5700 5750)(-5700 5450);
WIRE 16 -1 (-5850 5450)(-5700 5450);
WIRE 16 -1 (-5700 5450)(-5700 5350);
WIRE 16 -1 (-5700 5350)(-5700 5050);
WIRE 16 -1 (-5850 5350)(-5700 5350);
WIRE 16 -1 (-5850 5050)(-5700 5050);
WIRE 16 -1 (-5700 5050)(-5700 4800);
WIRE 16 -1 (-5500 7350)(-5500 8800);
WIRE 16 -1 (-5500 7350)(-5600 7350);
WIRE 16 -1 (-5600 7350)(-5600 7250);
WIRE 16 -1 (-5850 7350)(-5600 7350);
WIRE 16 -1 (-5600 7250)(-5850 7250);
WIRE 16 -1 (-7900 2800)(-7900 2900);
WIRE 16 -1 (-7350 2900)(-7900 2900);
WIRE 16 -1 (-7900 2950)(-7900 2900);
WIRE 16 -1 (-7350 2900)(-6900 2900);
WIRE 16 -1 (-7350 2700)(-7350 2900);
WIRE 16 -1 (-6900 2300)(-6900 2900);
WIRE 16 -1 (-6800 2300)(-6900 2300);
WIRE 16 -1 (-3850 2300)(-5900 2300);
FORCEPROP 2 LAST SIG_NAME PCIE_SMDAT
J 0
(-4460 2310);
DISPLAY 1.021277 (-4460 2310);
WIRE 16 -1 (-1350 3500)(-1350 3250);
WIRE 16 -1 (-550 3250)(-1350 3250);
FORCEPROP 2 LAST SIG_NAME PCIE_PERST_N
J 0
(-2160 3260);
DISPLAY 1.021277 (-2160 3260);
WIRE 16 -1 (-2250 3250)(-1350 3250);
WIRE 16 -1 (850 3850)(850 3650);
WIRE 16 -1 (850 3650)(1850 3650);
FORCEPROP 2 LAST SIG_NAME FPGA_IN_RST_DLY_N
J 0
(990 3660);
DISPLAY 1.021277 (990 3660);
WIRE 16 -1 (350 3650)(850 3650);
WIRE 16 -1 (650 3200)(650 3150);
WIRE 16 -1 (650 3150)(450 3150);
WIRE 16 -1 (450 3150)(450 3100);
WIRE 16 -1 (450 3250)(450 3150);
WIRE 16 -1 (450 3250)(350 3250);
DOT 1 (450 3150);
DOT 1 (-5500 4100);
DOT 1 (-5900 4100);
DOT 1 (-5900 3650);
DOT 1 (-7300 4950);
DOT 1 (-7350 2900);
DOT 1 (-7350 2100);
DOT 1 (-7900 2900);
DOT 1 (-7050 4100);
DOT 1 (-7350 8650);
DOT 1 (-7350 8050);
DOT 1 (-1300 7150);
DOT 1 (-700 5350);
DOT 1 (-7050 3650);
DOT 1 (-7350 8150);
DOT 1 (-7300 7550);
DOT 1 (-7300 6550);
DOT 1 (-7300 6350);
DOT 1 (-7300 6050);
DOT 1 (-7300 5650);
DOT 1 (-7300 5950);
DOT 1 (-7300 5550);
DOT 1 (-7300 5250);
DOT 1 (-7300 6850);
DOT 1 (-5700 6950);
DOT 1 (-5700 6650);
DOT 1 (-5700 6350);
DOT 1 (-5700 6150);
DOT 1 (-5700 5850);
DOT 1 (-5700 5750);
DOT 1 (-5700 5450);
DOT 1 (-5700 5350);
DOT 1 (-5600 7350);
DOT 1 (-5650 8050);
DOT 1 (-1250 7050);
DOT 1 (-1250 7150);
DOT 1 (-700 6150);
DOT 1 (-5700 5050);
DOT 1 (850 4250);
DOT 1 (850 3650);
DOT 1 (450 3500);
DOT 1 (-700 3950);
DOT 1 (-700 3650);
DOT 1 (-1350 3250);
DOT 1 (450 7150);
FORCENOTE
- THE LOGICAL LIBRARY FOR CPN:G229-10017-01 HAS NOT CREATED YET FOR THE CONCEPT HDL CAD 
(-1400 2500) 0;
DISPLAY LEFT (-1400 2500);
DISPLAY 1.021277 (-1400 2500);
FORCENOTE
- THUS, MANUALLY CHANGE U34 FROM G222-00082-01 TO G229-10017-01 FOR THE BOM FILE.
(-1400 2400) 0;
DISPLAY LEFT (-1400 2400);
DISPLAY 1.021277 (-1400 2400);
FORCENOTE
REV 2.1 [DVT]:
(-2650 2750) 0;
DISPLAY LEFT (-2650 2750);
DISPLAY 1.021277 (-2650 2750);
FORCENOTE
SMBUS BUFFER: RESERVED FOR THE FUTURE USE.
(-5600 1900) 0;
DISPLAY LEFT (-5600 1900);
DISPLAY 2.000000 (-5600 1900);
FORCENOTE
CT= 100NF, TD = 0.572S.
(650 3050) 0;
DISPLAY LEFT (650 3050);
DISPLAY 1.021277 (650 3050);
FORCENOTE
PART SHORTAGE ISSUE, CHANGE "SN74LVC1G17DCKR" TO "SN74LVC1G07DCKRG4".
(-700 6700) 0;
DISPLAY LEFT (-700 6700);
DISPLAY 1.021277 (-700 6700);
FORCENOTE
PCIE_X4_GF_CONN
(-5950 9900) 0;
DISPLAY LEFT (-5950 9900);
DISPLAY 4.914894 (-5950 9900);
FORCENOTE
- PART SHORTAGE, CHANGE CPN:G222-00082-01 MPN:TPS3808G33 TO CPN:G229-10017-01 MPN:TPS3808G30.
(-1950 2650) 0;
DISPLAY LEFT (-1950 2650);
DISPLAY 1.021277 (-1950 2650);
FORCENOTE
- SCHEMATIC RELEASE DATE: MAR 10, 2022.
(-1950 2750) 0;
DISPLAY LEFT (-1950 2750);
DISPLAY 1.021277 (-1950 2750);
FORCENOTE
- BOM NOTE:
(-1950 2500) 0;
DISPLAY LEFT (-1950 2500);
DISPLAY 1.021277 (-1950 2500);
QUIT
